FILE_TYPE = MACRO_DRAWING;
SET COLOR_WIRE YELLOW;
SET COLOR_PROP MONO;
SET COLOR_DOT WHITE;
SET COLOR_ARC YELLOW;
SET COLOR_BODY GREEN;
SET COLOR_NOTE MONO;
SET PROP_DISPLAY VALUE;
SET PAGE_NUMBER P147;
FORCEADD OFFPAGE..2
(2300 4250);
FORCEPROP 2 LAST $XR0 150 
J 0
(2489 4250);
DISPLAY 0.638298 (2489 4250);
PAINT MONO (2489 4250);
FORCEPROP 2 LAST PATH I10
J 0
(2675 4300);
DISPLAY 1.021277 (2675 4300);
PAINT ORANGE (2675 4300);
DISPLAY INVISIBLE (2675 4300);
FORCEPROP 2 LAST CDS_LIB mstr_standard
J 0
(2300 4250);
PAINT MONO (2300 4250);
DISPLAY INVISIBLE (2300 4250);
FORCEPROP 1 LAST OFFPAGE TRUE
J 0
(2625 4125);
DISPLAY 0.872340 (2625 4125);
PAINT GREEN (2625 4125);
DISPLAY INVISIBLE (2625 4125);
FORCEPROP 1 LAST COMMENT_BODY TRUE
J 0
(2255 4155);
DISPLAY 0.872340 (2255 4155);
PAINT GREEN (2255 4155);
DISPLAY INVISIBLE (2255 4155);
FORCEADD AST2520A1-GP-GP..6
(-1825 3400);
FORCEPROP 2 LASTPIN (-3375 3000) $PN Y5
J 2
(-3385 3010);
DISPLAY 0.808511 (-3385 3010);
PAINT ORANGE (-3385 3010);
FORCEPROP 2 LASTPIN (-3375 3750) $PN A3
J 2
(-3385 3760);
DISPLAY 0.808511 (-3385 3760);
PAINT ORANGE (-3385 3760);
FORCEPROP 2 LASTPIN (-3375 3100) $PN V6
J 2
(-3385 3110);
DISPLAY 0.808511 (-3385 3110);
PAINT ORANGE (-3385 3110);
FORCEPROP 2 LASTPIN (-3375 3450) $PN E10
J 2
(-3385 3460);
DISPLAY 0.808511 (-3385 3460);
PAINT ORANGE (-3385 3460);
FORCEPROP 2 LASTPIN (-3375 3500) $PN D8
J 2
(-3385 3510);
DISPLAY 0.808511 (-3385 3510);
PAINT ORANGE (-3385 3510);
FORCEPROP 1 LAST LOCATION U25W4
J 0
(-3225 4825);
DISPLAY 0.617021 (-3225 4825);
PAINT GREEN (-3225 4825);
FORCEPROP 1 LAST VALUE AST2520A1-GP-GP
J 0
(-3225 1950);
DISPLAY 0.617021 (-3225 1950);
PAINT GREEN (-3225 1950);
FORCEPROP 2 LASTPIN (-3375 4450) $PN C2
J 2
(-3385 4460);
DISPLAY 0.808511 (-3385 4460);
PAINT ORANGE (-3385 4460);
FORCEPROP 2 LASTPIN (-3375 4300) $PN E6
J 2
(-3385 4310);
DISPLAY 0.808511 (-3385 4310);
PAINT ORANGE (-3385 4310);
FORCEPROP 2 LASTPIN (-3375 4250) $PN D2
J 2
(-3385 4260);
DISPLAY 0.808511 (-3385 4260);
PAINT ORANGE (-3385 4260);
FORCEPROP 2 LASTPIN (-3375 4200) $PN D1
J 2
(-3385 4210);
DISPLAY 0.808511 (-3385 4210);
PAINT ORANGE (-3385 4210);
FORCEPROP 2 LASTPIN (-3375 4150) $PN C3
J 2
(-3385 4160);
DISPLAY 0.808511 (-3385 4160);
PAINT ORANGE (-3385 4160);
FORCEPROP 2 LASTPIN (-3375 4050) $PN B4
J 2
(-3385 4060);
DISPLAY 0.808511 (-3385 4060);
PAINT ORANGE (-3385 4060);
FORCEPROP 2 LASTPIN (-3375 4000) $PN A4
J 2
(-3385 4010);
DISPLAY 0.808511 (-3385 4010);
PAINT ORANGE (-3385 4010);
FORCEPROP 2 LASTPIN (-3375 3900) $PN C4
J 2
(-3385 3910);
DISPLAY 0.808511 (-3385 3910);
PAINT ORANGE (-3385 3910);
FORCEPROP 2 LASTPIN (-3375 3850) $PN C5
J 2
(-3385 3860);
DISPLAY 0.808511 (-3385 3860);
PAINT ORANGE (-3385 3860);
FORCEPROP 2 LASTPIN (-3375 3800) $PN D6
J 2
(-3385 3810);
DISPLAY 0.808511 (-3385 3810);
PAINT ORANGE (-3385 3810);
FORCEPROP 2 LASTPIN (-3375 4400) $PN C1
J 2
(-3385 4410);
DISPLAY 0.808511 (-3385 4410);
PAINT ORANGE (-3385 4410);
FORCEPROP 2 LASTPIN (-275 3800) $PN A5
J 0
(-265 3810);
DISPLAY 0.808511 (-265 3810);
PAINT ORANGE (-265 3810);
FORCEPROP 2 LASTPIN (-275 3750) $PN F9
J 0
(-265 3760);
DISPLAY 0.808511 (-265 3760);
PAINT ORANGE (-265 3760);
FORCEPROP 2 LASTPIN (-275 3900) $PN D7
J 0
(-265 3910);
DISPLAY 0.808511 (-265 3910);
PAINT ORANGE (-265 3910);
FORCEPROP 2 LASTPIN (-275 3850) $PN E7
J 0
(-265 3860);
DISPLAY 0.808511 (-265 3860);
PAINT ORANGE (-265 3860);
FORCEPROP 2 LASTPIN (-275 4000) $PN E9
J 0
(-265 4010);
DISPLAY 0.808511 (-265 4010);
PAINT ORANGE (-265 4010);
FORCEPROP 2 LASTPIN (-275 4050) $PN B5
J 0
(-265 4060);
DISPLAY 0.808511 (-265 4060);
PAINT ORANGE (-265 4060);
FORCEPROP 2 LASTPIN (-275 4150) $PN A2
J 0
(-265 4160);
DISPLAY 0.808511 (-265 4160);
PAINT ORANGE (-265 4160);
FORCEPROP 2 LASTPIN (-275 4200) $PN B3
J 0
(-265 4210);
DISPLAY 0.808511 (-265 4210);
PAINT ORANGE (-265 4210);
FORCEPROP 2 LASTPIN (-275 4300) $PN D4
J 0
(-265 4310);
DISPLAY 0.808511 (-265 4310);
PAINT ORANGE (-265 4310);
FORCEPROP 2 LASTPIN (-275 4250) $PN D5
J 0
(-265 4260);
DISPLAY 0.808511 (-265 4260);
PAINT ORANGE (-265 4260);
FORCEPROP 2 LASTPIN (-275 4450) $PN B2
J 0
(-265 4460);
DISPLAY 0.808511 (-265 4460);
PAINT ORANGE (-265 4460);
FORCEPROP 2 LASTPIN (-275 4400) $PN B1
J 0
(-265 4410);
DISPLAY 0.808511 (-265 4410);
PAINT ORANGE (-265 4410);
FORCEPROP 2 LASTPIN (-3375 2350) $PN U5
J 2
(-3385 2360);
DISPLAY 0.808511 (-3385 2360);
PAINT ORANGE (-3385 2360);
FORCEPROP 2 LASTPIN (-3375 2450) $PN V5
J 2
(-3385 2460);
DISPLAY 0.808511 (-3385 2460);
PAINT ORANGE (-3385 2460);
FORCEPROP 2 LASTPIN (-3375 2400) $PN U4
J 2
(-3385 2410);
DISPLAY 0.808511 (-3385 2410);
PAINT ORANGE (-3385 2410);
FORCEPROP 2 LASTPIN (-3375 2500) $PN AB4
J 2
(-3385 2510);
DISPLAY 0.808511 (-3385 2510);
PAINT ORANGE (-3385 2510);
FORCEPROP 2 LASTPIN (-3375 2600) $PN Y4
J 2
(-3385 2610);
DISPLAY 0.808511 (-3385 2610);
PAINT ORANGE (-3385 2610);
FORCEPROP 2 LASTPIN (-3375 2550) $PN AB3
J 2
(-3385 2560);
DISPLAY 0.808511 (-3385 2560);
PAINT ORANGE (-3385 2560);
FORCEPROP 2 LASTPIN (-3375 2750) $PN V4
J 2
(-3385 2760);
DISPLAY 0.808511 (-3385 2760);
PAINT ORANGE (-3385 2760);
FORCEPROP 2 LASTPIN (-3375 2700) $PN W4
J 2
(-3385 2710);
DISPLAY 0.808511 (-3385 2710);
PAINT ORANGE (-3385 2710);
FORCEPROP 2 LASTPIN (-3375 2650) $PN AA4
J 2
(-3385 2660);
DISPLAY 0.808511 (-3385 2660);
PAINT ORANGE (-3385 2660);
FORCEPROP 2 LASTPIN (-3375 2800) $PN W5
J 2
(-3385 2810);
DISPLAY 0.808511 (-3385 2810);
PAINT ORANGE (-3385 2810);
FORCEPROP 2 LASTPIN (-3375 2850) $PN AA5
J 2
(-3385 2860);
DISPLAY 0.808511 (-3385 2860);
PAINT ORANGE (-3385 2860);
FORCEPROP 2 LASTPIN (-3375 2950) $PN Y6
J 2
(-3385 2960);
DISPLAY 0.808511 (-3385 2960);
PAINT ORANGE (-3385 2960);
FORCEPROP 2 LASTPIN (-3375 2900) $PN AB5
J 2
(-3385 2910);
DISPLAY 0.808511 (-3385 2910);
PAINT ORANGE (-3385 2910);
FORCEPROP 2 LASTPIN (-275 2850) $PN F4
J 0
(-265 2860);
DISPLAY 0.808511 (-265 2860);
PAINT ORANGE (-265 2860);
FORCEPROP 2 LASTPIN (-275 2900) $PN F5
J 0
(-265 2910);
DISPLAY 0.808511 (-265 2910);
PAINT ORANGE (-265 2910);
FORCEPROP 2 LASTPIN (-275 2950) $PN E2
J 0
(-265 2960);
DISPLAY 0.808511 (-265 2960);
PAINT ORANGE (-265 2960);
FORCEPROP 2 LASTPIN (-275 3000) $PN E1
J 0
(-265 3010);
DISPLAY 0.808511 (-265 3010);
PAINT ORANGE (-265 3010);
FORCEPROP 2 LASTPIN (-275 3100) $PN E3
J 0
(-265 3110);
DISPLAY 0.808511 (-265 3110);
PAINT ORANGE (-265 3110);
FORCEPROP 2 LASTPIN (-275 3050) $PN F3
J 0
(-265 3060);
DISPLAY 0.808511 (-265 3060);
PAINT ORANGE (-265 3060);
FORCEPROP 2 LASTPIN (-275 3150) $PN G5
J 0
(-265 3160);
DISPLAY 0.808511 (-265 3160);
PAINT ORANGE (-265 3160);
FORCEPROP 2 LASTPIN (-275 3350) $PN G2
J 0
(-265 3360);
DISPLAY 0.808511 (-265 3360);
PAINT ORANGE (-265 3360);
FORCEPROP 2 LASTPIN (-275 3300) $PN G3
J 0
(-265 3310);
DISPLAY 0.808511 (-265 3310);
PAINT ORANGE (-265 3310);
FORCEPROP 2 LASTPIN (-275 3400) $PN F1
J 0
(-265 3410);
DISPLAY 0.808511 (-265 3410);
PAINT ORANGE (-265 3410);
FORCEPROP 2 LASTPIN (-275 3450) $PN H5
J 0
(-265 3460);
DISPLAY 0.808511 (-265 3460);
PAINT ORANGE (-265 3460);
FORCEPROP 2 LASTPIN (-275 3500) $PN G1
J 0
(-265 3510);
DISPLAY 0.808511 (-265 3510);
PAINT ORANGE (-265 3510);
FORCEPROP 2 LASTPIN (-275 3600) $PN H4
J 0
(-265 3610);
DISPLAY 0.808511 (-265 3610);
PAINT ORANGE (-265 3610);
FORCEPROP 2 LASTPIN (-275 3550) $PN H3
J 0
(-265 3560);
DISPLAY 0.808511 (-265 3560);
PAINT ORANGE (-265 3560);
FORCEPROP 2 LASTPIN (-275 2250) $PN H1
J 0
(-265 2260);
DISPLAY 0.808511 (-265 2260);
PAINT ORANGE (-265 2260);
FORCEPROP 2 LASTPIN (-275 2150) $PN J1
J 0
(-265 2160);
DISPLAY 0.808511 (-265 2160);
PAINT ORANGE (-265 2160);
FORCEPROP 2 LASTPIN (-275 2300) $PN H2
J 0
(-265 2310);
DISPLAY 0.808511 (-265 2310);
PAINT ORANGE (-265 2310);
FORCEPROP 2 LASTPIN (-275 2400) $PN V2
J 0
(-265 2410);
DISPLAY 0.808511 (-265 2410);
PAINT ORANGE (-265 2410);
FORCEPROP 2 LASTPIN (-275 2500) $PN V3
J 0
(-265 2510);
DISPLAY 0.808511 (-265 2510);
PAINT ORANGE (-265 2510);
FORCEPROP 2 LASTPIN (-275 2450) $PN W2
J 0
(-265 2460);
DISPLAY 0.808511 (-265 2460);
PAINT ORANGE (-265 2460);
FORCEPROP 2 LASTPIN (-275 2550) $PN U3
J 0
(-265 2560);
DISPLAY 0.808511 (-265 2560);
PAINT ORANGE (-265 2560);
FORCEPROP 2 LASTPIN (-275 2650) $PN AA3
J 0
(-265 2660);
DISPLAY 0.808511 (-265 2660);
PAINT ORANGE (-265 2660);
FORCEPROP 2 LASTPIN (-275 2600) $PN W3
J 0
(-265 2610);
DISPLAY 0.808511 (-265 2610);
PAINT ORANGE (-265 2610);
FORCEPROP 2 LASTPIN (-275 2750) $PN T4
J 0
(-265 2760);
DISPLAY 0.808511 (-265 2760);
PAINT ORANGE (-265 2760);
FORCEPROP 2 LASTPIN (-275 2700) $PN Y3
J 0
(-265 2710);
DISPLAY 0.808511 (-265 2710);
PAINT ORANGE (-265 2710);
FORCEPROP 2 LASTPIN (-3375 4650) $PN D3
J 2
(-3385 4660);
DISPLAY 0.808511 (-3385 4660);
PAINT ORANGE (-3385 4660);
FORCEPROP 2 LASTPIN (-275 4650) $PN B13
J 0
(-265 4660);
DISPLAY 0.808511 (-265 4660);
PAINT ORANGE (-265 4660);
FORCEPROP 2 LASTPIN (-275 4600) $PN C13
J 0
(-265 4610);
DISPLAY 0.808511 (-265 4610);
PAINT ORANGE (-265 4610);
FORCEPROP 2 LASTPIN (-275 3250) $PN F2
J 0
(-265 3260);
DISPLAY 0.808511 (-265 3260);
PAINT ORANGE (-265 3260);
FORCEPROP 2 LASTPIN (-275 3200) $PN G4
J 0
(-265 3210);
DISPLAY 0.808511 (-265 3210);
PAINT ORANGE (-265 3210);
FORCEPROP 2 LASTPIN (-3375 3050) $PN W6
J 2
(-3385 3060);
DISPLAY 0.808511 (-3385 3060);
PAINT ORANGE (-3385 3060);
FORCEPROP 2 LAST CDS_LIB w_hdl
J 0
(-1825 3400);
PAINT MONO (-1825 3400);
DISPLAY INVISIBLE (-1825 3400);
FORCEPROP 1 LAST PART_NUMBER 071.2520A.M001
J 0
(-1825 3400);
DISPLAY 0.617021 (-1825 3400);
PAINT GREEN (-1825 3400);
DISPLAY INVISIBLE (-1825 3400);
FORCEPROP 1 LAST PATH I106
J 0
(-1825 3400);
DISPLAY 0.617021 (-1825 3400);
PAINT GREEN (-1825 3400);
DISPLAY INVISIBLE (-1825 3400);
FORCEPROP 1 LAST CDS_LMAN_SYM_OUTLINE -1400,1400,1400,-1400
J 0
(-1825 3400);
DISPLAY 0.468085 (-1825 3400);
PAINT GREEN (-1825 3400);
DISPLAY INVISIBLE (-1825 3400);
FORCEPROP 1 LAST PACK_TYPE ASIC2-GB1
J 0
(-1825 3400);
DISPLAY 0.617021 (-1825 3400);
PAINT GREEN (-1825 3400);
DISPLAY INVISIBLE (-1825 3400);
FORCEPROP 2 LAST SEC 6
J 0
(-3225 4875);
DISPLAY 0.680851 (-3225 4875);
PAINT MONO (-3225 4875);
DISPLAY INVISIBLE (-3225 4875);
FORCEPROP 2 LAST SEC_TYPE ASIC2-GB1
J 0
(-3225 4875);
DISPLAY 1.021277 (-3225 4875);
PAINT ORANGE (-3225 4875);
DISPLAY INVISIBLE (-3225 4875);
FORCEADD OFFPAGE..2
(2300 4150);
FORCEPROP 2 LAST $XR1 139 
J 0
(2609 4150);
DISPLAY 0.638298 (2609 4150);
PAINT MONO (2609 4150);
FORCEPROP 2 LAST $XR0 121 
J 0
(2489 4150);
DISPLAY 0.638298 (2489 4150);
PAINT MONO (2489 4150);
FORCEPROP 2 LAST PATH I11
J 0
(2625 4200);
DISPLAY 1.021277 (2625 4200);
PAINT ORANGE (2625 4200);
DISPLAY INVISIBLE (2625 4200);
FORCEPROP 2 LAST CDS_LIB mstr_standard
J 0
(2300 4150);
PAINT ORANGE (2300 4150);
DISPLAY INVISIBLE (2300 4150);
FORCEPROP 1 LAST OFFPAGE TRUE
J 0
(2625 4025);
DISPLAY 0.872340 (2625 4025);
PAINT GREEN (2625 4025);
DISPLAY INVISIBLE (2625 4025);
FORCEPROP 1 LAST COMMENT_BODY TRUE
J 0
(2255 4055);
DISPLAY 0.872340 (2255 4055);
PAINT GREEN (2255 4055);
DISPLAY INVISIBLE (2255 4055);
FORCEADD OFFPAGE..1
R 2
(950 3000);
FORCEPROP 2 LAST $XR0 169 
J 0
(1136 3000);
DISPLAY 0.638298 (1136 3000);
PAINT MONO (1136 3000);
FORCEPROP 2 LAST PATH I111
J 0
(1125 3075);
DISPLAY 1.021277 (1125 3075);
PAINT ORANGE (1125 3075);
DISPLAY INVISIBLE (1125 3075);
FORCEPROP 2 LAST CDS_LIB mstr_standard
J 0
(950 3000);
PAINT MONO (950 3000);
DISPLAY INVISIBLE (950 3000);
FORCEPROP 1 LAST OFFPAGE TRUE
J 2
(625 2875);
DISPLAY 0.872340 (625 2875);
PAINT GREEN (625 2875);
DISPLAY INVISIBLE (625 2875);
FORCEPROP 1 LAST COMMENT_BODY TRUE
J 2
(825 2900);
DISPLAY 0.872340 (825 2900);
PAINT GREEN (825 2900);
DISPLAY INVISIBLE (825 2900);
FORCEADD OFFPAGE..1
R 2
(950 3200);
FORCEPROP 2 LAST $XR0 169 
J 0
(1136 3200);
DISPLAY 0.638298 (1136 3200);
PAINT MONO (1136 3200);
FORCEPROP 2 LAST PATH I115
J 0
(1125 3275);
DISPLAY 1.021277 (1125 3275);
PAINT ORANGE (1125 3275);
DISPLAY INVISIBLE (1125 3275);
FORCEPROP 2 LAST CDS_LIB mstr_standard
J 0
(950 3200);
PAINT MONO (950 3200);
DISPLAY INVISIBLE (950 3200);
FORCEPROP 1 LAST OFFPAGE TRUE
J 2
(625 3075);
DISPLAY 0.872340 (625 3075);
PAINT GREEN (625 3075);
DISPLAY INVISIBLE (625 3075);
FORCEPROP 1 LAST COMMENT_BODY TRUE
J 2
(825 3100);
DISPLAY 0.872340 (825 3100);
PAINT GREEN (825 3100);
DISPLAY INVISIBLE (825 3100);
FORCEADD OFFPAGE..2
R 2
(-4650 4400);
FORCEPROP 2 LAST $XR1 170 
J 0
(-5055 4400);
DISPLAY 0.638298 (-5055 4400);
PAINT MONO (-5055 4400);
FORCEPROP 2 LAST $XR0 119 
J 0
(-4935 4400);
DISPLAY 0.638298 (-4935 4400);
PAINT MONO (-4935 4400);
FORCEPROP 2 LAST PATH I116
J 2
(-4975 4450);
DISPLAY 1.021277 (-4975 4450);
PAINT ORANGE (-4975 4450);
DISPLAY INVISIBLE (-4975 4450);
FORCEPROP 2 LAST CDS_LIB mstr_standard
J 2
(-4650 4400);
PAINT MONO (-4650 4400);
DISPLAY INVISIBLE (-4650 4400);
FORCEPROP 1 LAST OFFPAGE TRUE
J 2
(-4975 4275);
DISPLAY 0.872340 (-4975 4275);
PAINT GREEN (-4975 4275);
DISPLAY INVISIBLE (-4975 4275);
FORCEPROP 1 LAST COMMENT_BODY TRUE
J 2
(-4605 4305);
DISPLAY 0.872340 (-4605 4305);
PAINT GREEN (-4605 4305);
DISPLAY INVISIBLE (-4605 4305);
FORCEADD OFFPAGE..2
(2300 4200);
FORCEPROP 2 LAST $XR1 139 
J 0
(2609 4200);
DISPLAY 0.638298 (2609 4200);
PAINT MONO (2609 4200);
FORCEPROP 2 LAST $XR0 121 
J 0
(2489 4200);
DISPLAY 0.638298 (2489 4200);
PAINT MONO (2489 4200);
FORCEPROP 2 LAST PATH I12
J 0
(2625 4250);
DISPLAY 1.021277 (2625 4250);
PAINT ORANGE (2625 4250);
DISPLAY INVISIBLE (2625 4250);
FORCEPROP 2 LAST CDS_LIB mstr_standard
J 0
(2300 4200);
PAINT MONO (2300 4200);
DISPLAY INVISIBLE (2300 4200);
FORCEPROP 1 LAST OFFPAGE TRUE
J 0
(2625 4075);
DISPLAY 0.872340 (2625 4075);
PAINT GREEN (2625 4075);
DISPLAY INVISIBLE (2625 4075);
FORCEPROP 1 LAST COMMENT_BODY TRUE
J 0
(2255 4105);
DISPLAY 0.872340 (2255 4105);
PAINT GREEN (2255 4105);
DISPLAY INVISIBLE (2255 4105);
FORCEADD OFFPAGE..5
R 2
(950 2650);
FORCEPROP 2 LAST $XR0 154 
J 0
(1139 2650);
DISPLAY 0.638298 (1139 2650);
PAINT MONO (1139 2650);
FORCEPROP 2 LAST CDS_LIB mstr_standard
J 2
(950 2650);
PAINT MONO (950 2650);
DISPLAY INVISIBLE (950 2650);
FORCEPROP 2 LAST PATH I126
J 2
(1200 2700);
DISPLAY 1.021277 (1200 2700);
PAINT ORANGE (1200 2700);
DISPLAY INVISIBLE (1200 2700);
FORCEPROP 1 LAST OFFPAGE TRUE
J 2
(625 2525);
DISPLAY 0.872340 (625 2525);
PAINT GREEN (625 2525);
DISPLAY INVISIBLE (625 2525);
FORCEPROP 1 LAST COMMENT_BODY TRUE
J 2
(850 2575);
DISPLAY 0.872340 (850 2575);
PAINT GREEN (850 2575);
DISPLAY INVISIBLE (850 2575);
FORCEADD OFFPAGE..2
(950 4650);
FORCEPROP 2 LAST $XR2 190 
J 0
(1379 4650);
DISPLAY 0.638298 (1379 4650);
PAINT MONO (1379 4650);
FORCEPROP 2 LAST $XR1 157 
J 0
(1259 4650);
DISPLAY 0.638298 (1259 4650);
PAINT MONO (1259 4650);
FORCEPROP 2 LAST $XR0 118 
J 0
(1139 4650);
DISPLAY 0.638298 (1139 4650);
PAINT MONO (1139 4650);
FORCEPROP 2 LAST CDS_LIB mstr_standard
J 0
(950 4650);
PAINT ORANGE (950 4650);
DISPLAY INVISIBLE (950 4650);
FORCEPROP 2 LAST PATH I127
J 0
(1400 4700);
DISPLAY 1.021277 (1400 4700);
PAINT ORANGE (1400 4700);
DISPLAY INVISIBLE (1400 4700);
FORCEPROP 1 LAST OFFPAGE TRUE
J 0
(1275 4525);
DISPLAY 0.872340 (1275 4525);
PAINT GREEN (1275 4525);
DISPLAY INVISIBLE (1275 4525);
FORCEPROP 1 LAST COMMENT_BODY TRUE
J 0
(905 4555);
DISPLAY 0.872340 (905 4555);
PAINT GREEN (905 4555);
DISPLAY INVISIBLE (905 4555);
FORCEADD OFFPAGE..2
(-3100 1500);
FORCEPROP 2 LAST $XR1 121 
J 0
(-2791 1500);
DISPLAY 0.638298 (-2791 1500);
PAINT MONO (-2791 1500);
FORCEPROP 2 LAST $XR0 125 
J 0
(-2911 1500);
DISPLAY 0.638298 (-2911 1500);
PAINT MONO (-2911 1500);
FORCEPROP 2 LAST CDS_LIB mstr_standard
J 0
(-3100 1500);
PAINT ORANGE (-3100 1500);
DISPLAY INVISIBLE (-3100 1500);
FORCEPROP 2 LAST PATH I128
J 0
(-2775 1550);
DISPLAY 1.021277 (-2775 1550);
PAINT ORANGE (-2775 1550);
DISPLAY INVISIBLE (-2775 1550);
FORCEPROP 1 LAST OFFPAGE TRUE
J 0
(-2775 1375);
DISPLAY 0.872340 (-2775 1375);
PAINT GREEN (-2775 1375);
DISPLAY INVISIBLE (-2775 1375);
FORCEPROP 1 LAST COMMENT_BODY TRUE
J 0
(-3145 1405);
DISPLAY 0.872340 (-3145 1405);
PAINT GREEN (-3145 1405);
DISPLAY INVISIBLE (-3145 1405);
FORCEADD RES..1
(-4100 1500);
FORCEPROP 1 LAST PACK_TYPE 0402
J 0
(-3800 1325);
DISPLAY 0.617021 (-3800 1325);
PAINT SKYBLUE (-3800 1325);
FORCEPROP 1 LASTPIN (-4000 1500) $PN 2
J 0
(-4038 1512);
DISPLAY 0.617021 (-4038 1512);
PAINT ORANGE (-4038 1512);
FORCEPROP 1 LAST LOCATION R1T24
J 0
(-4200 1375);
DISPLAY 0.617021 (-4200 1375);
PAINT AQUA (-4200 1375);
FORCEPROP 1 LAST VALUE 0.0
J 2
(-3975 1375);
DISPLAY 0.617021 (-3975 1375);
PAINT SKYBLUE (-3975 1375);
FORCEPROP 1 LAST WATTAGE 1/16W
J 2
(-4075 1325);
DISPLAY 0.617021 (-4075 1325);
PAINT SKYBLUE (-4075 1325);
FORCEPROP 1 LASTPIN (-4200 1500) $PN 1
J 0
(-4188 1512);
DISPLAY 0.617021 (-4188 1512);
PAINT ORANGE (-4188 1512);
FORCEPROP 1 LAST PART_NUMBER G21497-005
J 0
(-4050 1325);
DISPLAY 0.617021 (-4050 1325);
PAINT BLUE (-4050 1325);
FORCEPROP 1 LAST TOLERANCE 5%
J 0
(-3950 1375);
DISPLAY 0.617021 (-3950 1375);
PAINT SKYBLUE (-3950 1375);
FORCEPROP 1 LAST MATERIAL EMPTY
J 0
(-4000 1550);
DISPLAY 0.617021 (-4000 1550);
PAINT RED (-4000 1550);
FORCEPROP 1 LAST PATH I129
J 0
(-4150 1650);
DISPLAY 0.978723 (-4150 1650);
PAINT WHITE (-4150 1650);
DISPLAY INVISIBLE (-4150 1650);
FORCEPROP 0 LAST CDS_SEC 1
J 0
(-4000 1600);
PAINT MONO (-4000 1600);
DISPLAY INVISIBLE (-4000 1600);
FORCEPROP 2 LAST CDS_LIB mstr_discrete
J 0
(-4100 1500);
PAINT ORANGE (-4100 1500);
DISPLAY INVISIBLE (-4100 1500);
FORCEPROP 2 LAST CDS_LOCATION R1T24
J 0
(-4100 1525);
DISPLAY 0.617021 (-4100 1525);
PAINT AQUA (-4100 1525);
DISPLAY INVISIBLE (-4100 1525);
FORCEPROP 2 LAST SEC 1
J 0
(-4150 1700);
PAINT MONO (-4150 1700);
DISPLAY INVISIBLE (-4150 1700);
FORCEPROP 2 LAST SEC_TYPE 0402
J 0
(-4150 1700);
DISPLAY 1.021277 (-4150 1700);
PAINT ORANGE (-4150 1700);
DISPLAY INVISIBLE (-4150 1700);
FORCEADD OFFPAGE..2
(1850 4000);
FORCEPROP 2 LAST $XR1 186 
J 0
(2159 4000);
DISPLAY 0.638298 (2159 4000);
PAINT MONO (2159 4000);
FORCEPROP 2 LAST $XR0 150 
J 0
(2039 4000);
DISPLAY 0.638298 (2039 4000);
PAINT MONO (2039 4000);
FORCEPROP 2 LAST CDS_LIB mstr_standard
J 0
(1850 4000);
PAINT ORANGE (1850 4000);
DISPLAY INVISIBLE (1850 4000);
FORCEPROP 2 LAST PATH I13
J 0
(2050 4050);
DISPLAY 1.021277 (2050 4050);
PAINT ORANGE (2050 4050);
DISPLAY INVISIBLE (2050 4050);
FORCEPROP 1 LAST OFFPAGE TRUE
J 0
(2175 3875);
DISPLAY 0.872340 (2175 3875);
PAINT GREEN (2175 3875);
DISPLAY INVISIBLE (2175 3875);
FORCEPROP 1 LAST COMMENT_BODY TRUE
J 0
(1805 3905);
DISPLAY 0.872340 (1805 3905);
PAINT GREEN (1805 3905);
DISPLAY INVISIBLE (1805 3905);
FORCEADD OFFPAGE..1
R 2
(950 2850);
FORCEPROP 2 LAST $XR0 169 
J 0
(1136 2850);
DISPLAY 0.638298 (1136 2850);
PAINT MONO (1136 2850);
FORCEPROP 2 LAST CDS_LIB mstr_standard
J 0
(950 2850);
PAINT MONO (950 2850);
DISPLAY INVISIBLE (950 2850);
FORCEPROP 2 LAST PATH I131
J 0
(1125 2925);
DISPLAY 1.021277 (1125 2925);
PAINT ORANGE (1125 2925);
DISPLAY INVISIBLE (1125 2925);
FORCEPROP 1 LAST OFFPAGE TRUE
J 2
(625 2725);
DISPLAY 0.872340 (625 2725);
PAINT GREEN (625 2725);
DISPLAY INVISIBLE (625 2725);
FORCEPROP 1 LAST COMMENT_BODY TRUE
J 2
(825 2750);
DISPLAY 0.872340 (825 2750);
PAINT GREEN (825 2750);
DISPLAY INVISIBLE (825 2750);
FORCEADD OFFPAGE..1
R 2
(950 2900);
FORCEPROP 2 LAST $XR0 169 
J 0
(1136 2900);
DISPLAY 0.638298 (1136 2900);
PAINT MONO (1136 2900);
FORCEPROP 2 LAST CDS_LIB mstr_standard
J 0
(950 2900);
PAINT MONO (950 2900);
DISPLAY INVISIBLE (950 2900);
FORCEPROP 2 LAST PATH I132
J 0
(1125 2975);
DISPLAY 1.021277 (1125 2975);
PAINT ORANGE (1125 2975);
DISPLAY INVISIBLE (1125 2975);
FORCEPROP 1 LAST OFFPAGE TRUE
J 2
(625 2775);
DISPLAY 0.872340 (625 2775);
PAINT GREEN (625 2775);
DISPLAY INVISIBLE (625 2775);
FORCEPROP 1 LAST COMMENT_BODY TRUE
J 2
(825 2800);
DISPLAY 0.872340 (825 2800);
PAINT GREEN (825 2800);
DISPLAY INVISIBLE (825 2800);
FORCEADD OFFPAGE..1
R 2
(950 2950);
FORCEPROP 2 LAST $XR0 169 
J 0
(1136 2950);
DISPLAY 0.638298 (1136 2950);
PAINT MONO (1136 2950);
FORCEPROP 2 LAST CDS_LIB mstr_standard
J 0
(950 2950);
PAINT MONO (950 2950);
DISPLAY INVISIBLE (950 2950);
FORCEPROP 2 LAST PATH I134
J 0
(1125 3025);
DISPLAY 1.021277 (1125 3025);
PAINT ORANGE (1125 3025);
DISPLAY INVISIBLE (1125 3025);
FORCEPROP 1 LAST OFFPAGE TRUE
J 2
(625 2825);
DISPLAY 0.872340 (625 2825);
PAINT GREEN (625 2825);
DISPLAY INVISIBLE (625 2825);
FORCEPROP 1 LAST COMMENT_BODY TRUE
J 2
(825 2850);
DISPLAY 0.872340 (825 2850);
PAINT GREEN (825 2850);
DISPLAY INVISIBLE (825 2850);
FORCEADD OFFPAGE..1
R 2
(950 3050);
FORCEPROP 2 LAST $XR0 169 
J 0
(1136 3050);
DISPLAY 0.638298 (1136 3050);
PAINT MONO (1136 3050);
FORCEPROP 2 LAST CDS_LIB mstr_standard
J 0
(950 3050);
PAINT MONO (950 3050);
DISPLAY INVISIBLE (950 3050);
FORCEPROP 2 LAST PATH I135
J 0
(1125 3125);
DISPLAY 1.021277 (1125 3125);
PAINT ORANGE (1125 3125);
DISPLAY INVISIBLE (1125 3125);
FORCEPROP 1 LAST OFFPAGE TRUE
J 2
(625 2925);
DISPLAY 0.872340 (625 2925);
PAINT GREEN (625 2925);
DISPLAY INVISIBLE (625 2925);
FORCEPROP 1 LAST COMMENT_BODY TRUE
J 2
(825 2950);
DISPLAY 0.872340 (825 2950);
PAINT GREEN (825 2950);
DISPLAY INVISIBLE (825 2950);
FORCEADD OFFPAGE..1
R 2
(950 3100);
FORCEPROP 2 LAST $XR0 169 
J 0
(1136 3100);
DISPLAY 0.638298 (1136 3100);
PAINT MONO (1136 3100);
FORCEPROP 2 LAST CDS_LIB mstr_standard
J 2
(950 3100);
PAINT MONO (950 3100);
DISPLAY INVISIBLE (950 3100);
FORCEPROP 2 LAST PATH I137
J 0
(1125 3175);
DISPLAY 1.021277 (1125 3175);
PAINT ORANGE (1125 3175);
DISPLAY INVISIBLE (1125 3175);
FORCEPROP 1 LAST OFFPAGE TRUE
J 2
(625 2975);
DISPLAY 0.872340 (625 2975);
PAINT GREEN (625 2975);
DISPLAY INVISIBLE (625 2975);
FORCEPROP 1 LAST COMMENT_BODY TRUE
J 2
(825 3000);
DISPLAY 0.872340 (825 3000);
PAINT GREEN (825 3000);
DISPLAY INVISIBLE (825 3000);
FORCEADD OFFPAGE..1
R 2
(950 3150);
FORCEPROP 2 LAST $XR0 169 
J 0
(1136 3150);
DISPLAY 0.638298 (1136 3150);
PAINT MONO (1136 3150);
FORCEPROP 2 LAST CDS_LIB mstr_standard
J 0
(950 3150);
PAINT MONO (950 3150);
DISPLAY INVISIBLE (950 3150);
FORCEPROP 2 LAST PATH I138
J 0
(1125 3225);
DISPLAY 1.021277 (1125 3225);
PAINT ORANGE (1125 3225);
DISPLAY INVISIBLE (1125 3225);
FORCEPROP 1 LAST OFFPAGE TRUE
J 2
(625 3025);
DISPLAY 0.872340 (625 3025);
PAINT GREEN (625 3025);
DISPLAY INVISIBLE (625 3025);
FORCEPROP 1 LAST COMMENT_BODY TRUE
J 2
(825 3050);
DISPLAY 0.872340 (825 3050);
PAINT GREEN (825 3050);
DISPLAY INVISIBLE (825 3050);
FORCEADD OFFPAGE..1
(-4650 4050);
FORCEPROP 2 LAST $XR0 101 
J 0
(-4902 4050);
DISPLAY 0.638298 (-4902 4050);
PAINT MONO (-4902 4050);
FORCEPROP 2 LAST PATH I139
J 0
(-4900 4100);
DISPLAY 1.021277 (-4900 4100);
PAINT ORANGE (-4900 4100);
DISPLAY INVISIBLE (-4900 4100);
FORCEPROP 2 LAST CDS_LIB mstr_standard
J 0
(-4650 4050);
PAINT ORANGE (-4650 4050);
DISPLAY INVISIBLE (-4650 4050);
FORCEPROP 1 LAST OFFPAGE TRUE
J 0
(-4325 3925);
DISPLAY 0.872340 (-4325 3925);
PAINT GREEN (-4325 3925);
DISPLAY INVISIBLE (-4325 3925);
FORCEPROP 1 LAST COMMENT_BODY TRUE
J 0
(-4525 3950);
DISPLAY 0.872340 (-4525 3950);
PAINT GREEN (-4525 3950);
DISPLAY INVISIBLE (-4525 3950);
FORCEADD OFFPAGE..2
(1850 3900);
FORCEPROP 2 LAST $XR0 150 
J 0
(2039 3900);
DISPLAY 0.638298 (2039 3900);
PAINT MONO (2039 3900);
FORCEPROP 2 LAST CDS_LIB mstr_standard
J 0
(1850 3900);
PAINT MONO (1850 3900);
DISPLAY INVISIBLE (1850 3900);
FORCEPROP 2 LAST PATH I14
J 0
(2050 3950);
DISPLAY 1.021277 (2050 3950);
PAINT ORANGE (2050 3950);
DISPLAY INVISIBLE (2050 3950);
FORCEPROP 1 LAST OFFPAGE TRUE
J 0
(2175 3775);
DISPLAY 0.872340 (2175 3775);
PAINT GREEN (2175 3775);
DISPLAY INVISIBLE (2175 3775);
FORCEPROP 1 LAST COMMENT_BODY TRUE
J 0
(1805 3805);
DISPLAY 0.872340 (1805 3805);
PAINT GREEN (1805 3805);
DISPLAY INVISIBLE (1805 3805);
FORCEADD OFFPAGE..1
(-4650 4450);
FORCEPROP 2 LAST $XR0 101 
J 0
(-4902 4450);
DISPLAY 0.638298 (-4902 4450);
PAINT MONO (-4902 4450);
FORCEPROP 2 LAST CDS_LIB mstr_standard
J 0
(-4650 4450);
PAINT ORANGE (-4650 4450);
DISPLAY INVISIBLE (-4650 4450);
FORCEPROP 2 LAST PATH I140
J 0
(-4900 4500);
DISPLAY 1.021277 (-4900 4500);
PAINT ORANGE (-4900 4500);
DISPLAY INVISIBLE (-4900 4500);
FORCEPROP 1 LAST OFFPAGE TRUE
J 0
(-4325 4325);
DISPLAY 0.872340 (-4325 4325);
PAINT GREEN (-4325 4325);
DISPLAY INVISIBLE (-4325 4325);
FORCEPROP 1 LAST COMMENT_BODY TRUE
J 0
(-4525 4350);
DISPLAY 0.872340 (-4525 4350);
PAINT GREEN (-4525 4350);
DISPLAY INVISIBLE (-4525 4350);
FORCEADD OFFPAGE..2
(950 2750);
FORCEPROP 2 LAST $XR1 108 
J 0
(1229 2750);
DISPLAY 0.638298 (1229 2750);
PAINT MONO (1229 2750);
FORCEPROP 2 LAST $XR0 95 
J 0
(1139 2750);
DISPLAY 0.638298 (1139 2750);
PAINT MONO (1139 2750);
FORCEPROP 2 LAST ROOM SMART_CLST
J 0
(700 2825);
DISPLAY 1.361702 (700 2825);
PAINT ORANGE (700 2825);
DISPLAY INVISIBLE (700 2825);
FORCEPROP 2 LAST CDS_LIB mstr_standard
J 0
(950 2750);
PAINT ORANGE (950 2750);
DISPLAY INVISIBLE (950 2750);
FORCEPROP 2 LAST PATH I143
J 0
(1150 2800);
DISPLAY 1.021277 (1150 2800);
PAINT ORANGE (1150 2800);
DISPLAY INVISIBLE (1150 2800);
FORCEPROP 1 LAST OFFPAGE TRUE
J 0
(1275 2625);
PAINT GREEN (1275 2625);
DISPLAY INVISIBLE (1275 2625);
FORCEPROP 1 LAST COMMENT_BODY TRUE
J 0
(905 2655);
DISPLAY 1.170213 (905 2655);
PAINT GREEN (905 2655);
DISPLAY INVISIBLE (905 2655);
FORCEADD OFFPAGE..1
R 2
(950 3500);
FORCEPROP 2 LAST $XR0 152 
J 0
(1136 3500);
DISPLAY 0.638298 (1136 3500);
PAINT MONO (1136 3500);
FORCEPROP 2 LAST ROOM BMC
J 2
(1200 3575);
DISPLAY 1.361702 (1200 3575);
PAINT ORANGE (1200 3575);
DISPLAY INVISIBLE (1200 3575);
FORCEPROP 2 LAST BOM_COST SM_CONTROLLER
J 2
(500 3550);
PAINT MONO (500 3550);
DISPLAY INVISIBLE (500 3550);
FORCEPROP 2 LAST PATH I144
J 2
(1200 3550);
DISPLAY 1.021277 (1200 3550);
PAINT ORANGE (1200 3550);
DISPLAY INVISIBLE (1200 3550);
FORCEPROP 2 LAST CDS_LIB mstr_standard
J 2
(950 3500);
PAINT MONO (950 3500);
DISPLAY INVISIBLE (950 3500);
FORCEPROP 1 LAST OFFPAGE TRUE
J 2
(625 3375);
DISPLAY 0.872340 (625 3375);
PAINT GREEN (625 3375);
DISPLAY INVISIBLE (625 3375);
FORCEPROP 1 LAST COMMENT_BODY TRUE
J 2
(825 3400);
DISPLAY 0.872340 (825 3400);
PAINT GREEN (825 3400);
DISPLAY INVISIBLE (825 3400);
FORCEADD GND..1
R 1
(100 3350);
FORCEPROP 3 LASTPIN (50 3350) SIG_NAME GND\g
J 0
(60 3360);
DISPLAY 0.659574 (60 3360);
PAINT MONO (60 3360);
DISPLAY INVISIBLE (60 3360);
FORCEPROP 1 LAST VOLTAGE 0.0V
R 1
J 0
(143 3305);
DISPLAY 0.340426 (143 3305);
PAINT GREEN (143 3305);
DISPLAY INVISIBLE (143 3305);
FORCEPROP 1 LAST SIZE 1B
R 1
J 0
(150 3425);
DISPLAY 0.872340 (150 3425);
PAINT AQUA (150 3425);
DISPLAY INVISIBLE (150 3425);
FORCEPROP 1 LAST PATH I145
R 1
J 0
(100 3425);
DISPLAY 0.872340 (100 3425);
PAINT AQUA (100 3425);
DISPLAY INVISIBLE (100 3425);
FORCEPROP 2 LAST CDS_LIB mstr_symbols
R 1
J 0
(100 3350);
PAINT MONO (100 3350);
DISPLAY INVISIBLE (100 3350);
FORCEPROP 1 LAST BODY_TYPE PLUMBING
R 1
J 0
(143 3305);
DISPLAY 0.340426 (143 3305);
PAINT GREEN (143 3305);
DISPLAY INVISIBLE (143 3305);
FORCEPROP 1 LAST HDL_POWER GND
R 1
J 0
(-50 3350);
DISPLAY 0.872340 (-50 3350);
PAINT GREEN (-50 3350);
DISPLAY INVISIBLE (-50 3350);
FORCEADD OFFPAGE..1
R 2
(950 4600);
FORCEPROP 2 LAST $XR1 182 
J 0
(1256 4600);
DISPLAY 0.638298 (1256 4600);
PAINT MONO (1256 4600);
FORCEPROP 2 LAST $XR0 119 
J 0
(1136 4600);
DISPLAY 0.638298 (1136 4600);
PAINT MONO (1136 4600);
FORCEPROP 2 LAST CDS_LIB mstr_standard
J 0
(950 4600);
PAINT MONO (950 4600);
DISPLAY INVISIBLE (950 4600);
FORCEPROP 2 LAST PATH I146
J 0
(1125 4675);
DISPLAY 1.021277 (1125 4675);
PAINT ORANGE (1125 4675);
DISPLAY INVISIBLE (1125 4675);
FORCEPROP 2 LAST ROOM BMC
J 2
(1200 4675);
DISPLAY 1.361702 (1200 4675);
PAINT ORANGE (1200 4675);
DISPLAY INVISIBLE (1200 4675);
FORCEPROP 2 LAST BOM_COST SM_CONTROLLER
J 2
(500 4650);
PAINT MONO (500 4650);
DISPLAY INVISIBLE (500 4650);
FORCEPROP 1 LAST OFFPAGE TRUE
J 2
(625 4475);
DISPLAY 0.872340 (625 4475);
PAINT GREEN (625 4475);
DISPLAY INVISIBLE (625 4475);
FORCEPROP 1 LAST COMMENT_BODY TRUE
J 2
(825 4500);
DISPLAY 0.872340 (825 4500);
PAINT GREEN (825 4500);
DISPLAY INVISIBLE (825 4500);
FORCEADD OFFPAGE..1
R 2
(950 3450);
FORCEPROP 2 LAST $XR0 152 
J 0
(1136 3450);
DISPLAY 0.638298 (1136 3450);
PAINT MONO (1136 3450);
FORCEPROP 2 LAST CDS_LIB mstr_standard
J 2
(950 3450);
PAINT MONO (950 3450);
DISPLAY INVISIBLE (950 3450);
FORCEPROP 2 LAST PATH I147
J 2
(1200 3500);
DISPLAY 1.021277 (1200 3500);
PAINT ORANGE (1200 3500);
DISPLAY INVISIBLE (1200 3500);
FORCEPROP 2 LAST ROOM BMC
J 2
(1200 3525);
DISPLAY 1.361702 (1200 3525);
PAINT ORANGE (1200 3525);
DISPLAY INVISIBLE (1200 3525);
FORCEPROP 2 LAST BOM_COST SM_CONTROLLER
J 2
(500 3500);
PAINT MONO (500 3500);
DISPLAY INVISIBLE (500 3500);
FORCEPROP 1 LAST OFFPAGE TRUE
J 2
(625 3325);
DISPLAY 0.872340 (625 3325);
PAINT GREEN (625 3325);
DISPLAY INVISIBLE (625 3325);
FORCEPROP 1 LAST COMMENT_BODY TRUE
J 2
(825 3350);
DISPLAY 0.872340 (825 3350);
PAINT GREEN (825 3350);
DISPLAY INVISIBLE (825 3350);
FORCEADD OFFPAGE..5
(-4650 4000);
FORCEPROP 2 LAST $XR1 177 
J 0
(-5055 4000);
DISPLAY 0.638298 (-5055 4000);
PAINT MONO (-5055 4000);
FORCEPROP 2 LAST $XR0 119 
J 0
(-4935 4000);
DISPLAY 0.638298 (-4935 4000);
PAINT MONO (-4935 4000);
FORCEPROP 2 LAST CDS_LIB mstr_standard
J 0
(-4650 4000);
PAINT ORANGE (-4650 4000);
DISPLAY INVISIBLE (-4650 4000);
FORCEPROP 2 LAST PATH I148
J 0
(-4925 4050);
DISPLAY 1.021277 (-4925 4050);
PAINT ORANGE (-4925 4050);
DISPLAY INVISIBLE (-4925 4050);
FORCEPROP 1 LAST OFFPAGE TRUE
J 0
(-4325 3875);
DISPLAY 0.872340 (-4325 3875);
PAINT GREEN (-4325 3875);
DISPLAY INVISIBLE (-4325 3875);
FORCEPROP 1 LAST COMMENT_BODY TRUE
J 0
(-4550 3925);
DISPLAY 0.872340 (-4550 3925);
PAINT GREEN (-4550 3925);
DISPLAY INVISIBLE (-4550 3925);
FORCEADD OFFPAGE..1
R 2
(950 3600);
FORCEPROP 2 LAST $XR0 152 
J 0
(1136 3600);
DISPLAY 0.638298 (1136 3600);
PAINT MONO (1136 3600);
FORCEPROP 2 LAST BOM_COST SM_CONTROLLER
J 2
(500 3650);
PAINT MONO (500 3650);
DISPLAY INVISIBLE (500 3650);
FORCEPROP 2 LAST ROOM BMC
J 2
(1200 3675);
DISPLAY 1.361702 (1200 3675);
PAINT ORANGE (1200 3675);
DISPLAY INVISIBLE (1200 3675);
FORCEPROP 2 LAST CDS_LIB mstr_standard
J 2
(950 3600);
PAINT ORANGE (950 3600);
DISPLAY INVISIBLE (950 3600);
FORCEPROP 2 LAST PATH I149
J 2
(1200 3650);
DISPLAY 1.021277 (1200 3650);
PAINT ORANGE (1200 3650);
DISPLAY INVISIBLE (1200 3650);
FORCEPROP 1 LAST OFFPAGE TRUE
J 2
(625 3475);
DISPLAY 0.872340 (625 3475);
PAINT GREEN (625 3475);
DISPLAY INVISIBLE (625 3475);
FORCEPROP 1 LAST COMMENT_BODY TRUE
J 2
(825 3500);
DISPLAY 0.872340 (825 3500);
PAINT GREEN (825 3500);
DISPLAY INVISIBLE (825 3500);
FORCEADD OFFPAGE..2
(1850 3850);
FORCEPROP 2 LAST $XR0 150 
J 0
(2039 3850);
DISPLAY 0.638298 (2039 3850);
PAINT MONO (2039 3850);
FORCEPROP 2 LAST CDS_LIB mstr_standard
J 0
(1850 3850);
PAINT MONO (1850 3850);
DISPLAY INVISIBLE (1850 3850);
FORCEPROP 2 LAST PATH I15
J 0
(2475 3900);
DISPLAY 1.021277 (2475 3900);
PAINT ORANGE (2475 3900);
DISPLAY INVISIBLE (2475 3900);
FORCEPROP 1 LAST OFFPAGE TRUE
J 0
(2175 3725);
DISPLAY 0.872340 (2175 3725);
PAINT GREEN (2175 3725);
DISPLAY INVISIBLE (2175 3725);
FORCEPROP 1 LAST COMMENT_BODY TRUE
J 0
(1805 3755);
DISPLAY 0.872340 (1805 3755);
PAINT GREEN (1805 3755);
DISPLAY INVISIBLE (1805 3755);
FORCEADD OFFPAGE..1
R 2
(950 3550);
FORCEPROP 2 LAST $XR0 152 
J 0
(1136 3550);
DISPLAY 0.638298 (1136 3550);
PAINT MONO (1136 3550);
FORCEPROP 2 LAST PATH I150
J 2
(1200 3600);
DISPLAY 1.021277 (1200 3600);
PAINT ORANGE (1200 3600);
DISPLAY INVISIBLE (1200 3600);
FORCEPROP 2 LAST ROOM BMC
J 2
(1200 3625);
DISPLAY 1.361702 (1200 3625);
PAINT ORANGE (1200 3625);
DISPLAY INVISIBLE (1200 3625);
FORCEPROP 2 LAST BOM_COST SM_CONTROLLER
J 2
(500 3600);
PAINT MONO (500 3600);
DISPLAY INVISIBLE (500 3600);
FORCEPROP 2 LAST CDS_LIB mstr_standard
J 2
(950 3550);
PAINT MONO (950 3550);
DISPLAY INVISIBLE (950 3550);
FORCEPROP 1 LAST OFFPAGE TRUE
J 2
(625 3425);
DISPLAY 0.872340 (625 3425);
PAINT GREEN (625 3425);
DISPLAY INVISIBLE (625 3425);
FORCEPROP 1 LAST COMMENT_BODY TRUE
J 2
(825 3450);
DISPLAY 0.872340 (825 3450);
PAINT GREEN (825 3450);
DISPLAY INVISIBLE (825 3450);
FORCEADD RES..2
(900 1950);
FORCEPROP 1 LASTPIN (900 1850) $PN 2
J 0
(905 1860);
DISPLAY 0.787234 (905 1860);
PAINT ORANGE (905 1860);
FORCEPROP 1 LAST MATERIAL CHIP
J 0
(940 1875);
DISPLAY 0.617021 (940 1875);
PAINT SKYBLUE (940 1875);
FORCEPROP 1 LAST WATTAGE 1/16W
J 0
(940 1925);
DISPLAY 0.617021 (940 1925);
PAINT SKYBLUE (940 1925);
FORCEPROP 1 LAST PART_NUMBER G21796-048
J 0
(940 1825);
DISPLAY 0.617021 (940 1825);
PAINT BLUE (940 1825);
FORCEPROP 1 LAST PACK_TYPE 0402
J 0
(940 1775);
DISPLAY 0.617021 (940 1775);
PAINT SKYBLUE (940 1775);
FORCEPROP 1 LASTPIN (900 2050) $PN 1
J 0
(905 2012);
DISPLAY 0.787234 (905 2012);
PAINT ORANGE (905 2012);
FORCEPROP 1 LAST TOLERANCE 1%
J 0
(945 1975);
DISPLAY 0.617021 (945 1975);
PAINT SKYBLUE (945 1975);
FORCEPROP 1 LAST VALUE 49.9K
J 0
(945 2025);
DISPLAY 0.617021 (945 2025);
PAINT SKYBLUE (945 2025);
FORCEPROP 1 LAST LOCATION R25W57
J 0
(945 2075);
DISPLAY 0.617021 (945 2075);
PAINT AQUA (945 2075);
FORCEPROP 0 LAST SEC 1
J 0
(950 2125);
DISPLAY 0.680851 (950 2125);
PAINT MONO (950 2125);
DISPLAY INVISIBLE (950 2125);
FORCEPROP 2 LAST SEC_TYPE 0402
J 0
(950 2175);
DISPLAY 1.021277 (950 2175);
PAINT ORANGE (950 2175);
DISPLAY INVISIBLE (950 2175);
FORCEPROP 2 LAST ROOM V_SUPER
J 0
(950 2125);
DISPLAY 1.021277 (950 2125);
PAINT ORANGE (950 2125);
DISPLAY INVISIBLE (950 2125);
FORCEPROP 2 LAST CDS_LIB mstr_discrete
J 0
(900 1950);
PAINT MONO (900 1950);
DISPLAY INVISIBLE (900 1950);
FORCEPROP 1 LAST PATH I151
J 0
(950 2125);
DISPLAY 0.978723 (950 2125);
PAINT WHITE (950 2125);
DISPLAY INVISIBLE (950 2125);
FORCEADD OFFPAGE..4
R 2
(-4650 3500);
FORCEPROP 2 LAST $XR2 119 
J 0
(-5142 3500);
DISPLAY 0.638298 (-5142 3500);
PAINT MONO (-5142 3500);
FORCEPROP 2 LAST $XR1 133 
J 0
(-5022 3500);
DISPLAY 0.638298 (-5022 3500);
PAINT MONO (-5022 3500);
FORCEPROP 2 LAST $XR0 108 
J 0
(-4902 3500);
DISPLAY 0.638298 (-4902 3500);
PAINT MONO (-4902 3500);
FORCEPROP 2 LAST PATH I152
J 2
(-4975 3550);
DISPLAY 1.021277 (-4975 3550);
PAINT ORANGE (-4975 3550);
DISPLAY INVISIBLE (-4975 3550);
FORCEPROP 2 LAST CDS_LIB mstr_standard
J 2
(-4650 3500);
PAINT ORANGE (-4650 3500);
DISPLAY INVISIBLE (-4650 3500);
FORCEPROP 1 LAST OFFPAGE TRUE
J 2
(-4975 3375);
PAINT GREEN (-4975 3375);
DISPLAY INVISIBLE (-4975 3375);
FORCEPROP 1 LAST COMMENT_BODY TRUE
J 2
(-4625 3400);
DISPLAY 1.404255 (-4625 3400);
PAINT PEACH (-4625 3400);
DISPLAY INVISIBLE (-4625 3400);
FORCEADD OFFPAGE..4
R 2
(-4650 3450);
FORCEPROP 2 LAST $XR2 119 
J 0
(-5142 3450);
DISPLAY 0.638298 (-5142 3450);
PAINT MONO (-5142 3450);
FORCEPROP 2 LAST $XR1 133 
J 0
(-5022 3450);
DISPLAY 0.638298 (-5022 3450);
PAINT MONO (-5022 3450);
FORCEPROP 2 LAST $XR0 108 
J 0
(-4902 3450);
DISPLAY 0.638298 (-4902 3450);
PAINT MONO (-4902 3450);
FORCEPROP 2 LAST PATH I153
J 2
(-4975 3500);
DISPLAY 1.021277 (-4975 3500);
PAINT ORANGE (-4975 3500);
DISPLAY INVISIBLE (-4975 3500);
FORCEPROP 2 LAST CDS_LIB mstr_standard
J 2
(-4650 3450);
PAINT ORANGE (-4650 3450);
DISPLAY INVISIBLE (-4650 3450);
FORCEPROP 1 LAST OFFPAGE TRUE
J 2
(-4975 3325);
PAINT GREEN (-4975 3325);
DISPLAY INVISIBLE (-4975 3325);
FORCEPROP 1 LAST COMMENT_BODY TRUE
J 2
(-4625 3350);
DISPLAY 1.404255 (-4625 3350);
PAINT PEACH (-4625 3350);
DISPLAY INVISIBLE (-4625 3350);
FORCEADD OFFPAGE..2
(950 2700);
FORCEPROP 2 LAST $XR0 251 
J 0
(1139 2700);
DISPLAY 0.638298 (1139 2700);
PAINT MONO (1139 2700);
FORCEPROP 2 LAST PATH I154
J 0
(1250 2750);
DISPLAY 1.021277 (1250 2750);
PAINT ORANGE (1250 2750);
DISPLAY INVISIBLE (1250 2750);
FORCEPROP 2 LAST CDS_LIB mstr_standard
J 0
(950 2700);
PAINT ORANGE (950 2700);
DISPLAY INVISIBLE (950 2700);
FORCEPROP 2 LAST ROOM SMART_CLST
J 0
(700 2775);
DISPLAY 1.361702 (700 2775);
PAINT ORANGE (700 2775);
DISPLAY INVISIBLE (700 2775);
FORCEPROP 1 LAST OFFPAGE TRUE
J 0
(1275 2575);
PAINT GREEN (1275 2575);
DISPLAY INVISIBLE (1275 2575);
FORCEPROP 1 LAST COMMENT_BODY TRUE
J 0
(905 2605);
DISPLAY 1.170213 (905 2605);
PAINT GREEN (905 2605);
DISPLAY INVISIBLE (905 2605);
FORCEADD OFFPAGE..1
(-4850 2600);
FORCEPROP 2 LAST $XR0 251 
J 0
(-5102 2600);
DISPLAY 0.638298 (-5102 2600);
PAINT MONO (-5102 2600);
FORCEPROP 2 LAST PATH I155
J 0
(-5100 2650);
DISPLAY 1.021277 (-5100 2650);
PAINT ORANGE (-5100 2650);
DISPLAY INVISIBLE (-5100 2650);
FORCEPROP 2 LAST CDS_LIB mstr_standard
J 0
(-4850 2600);
PAINT ORANGE (-4850 2600);
DISPLAY INVISIBLE (-4850 2600);
FORCEPROP 1 LAST OFFPAGE TRUE
J 0
(-4525 2475);
DISPLAY 0.872340 (-4525 2475);
PAINT GREEN (-4525 2475);
DISPLAY INVISIBLE (-4525 2475);
FORCEPROP 1 LAST COMMENT_BODY TRUE
J 0
(-4725 2500);
DISPLAY 0.872340 (-4725 2500);
PAINT GREEN (-4725 2500);
DISPLAY INVISIBLE (-4725 2500);
FORCEADD RES..2
(-4700 1950);
FORCEPROP 1 LASTPIN (-4700 1850) $PN 2
J 0
(-4695 1860);
DISPLAY 0.617021 (-4695 1860);
PAINT ORANGE (-4695 1860);
FORCEPROP 1 LAST WATTAGE 1/16W
J 0
(-4660 1925);
DISPLAY 0.617021 (-4660 1925);
PAINT SKYBLUE (-4660 1925);
FORCEPROP 1 LAST MATERIAL CHIP
J 0
(-4660 1875);
DISPLAY 0.617021 (-4660 1875);
PAINT SKYBLUE (-4660 1875);
FORCEPROP 1 LAST PACK_TYPE 0402
J 0
(-4660 1775);
DISPLAY 0.617021 (-4660 1775);
PAINT SKYBLUE (-4660 1775);
FORCEPROP 1 LASTPIN (-4700 2050) $PN 1
J 0
(-4695 2012);
DISPLAY 0.617021 (-4695 2012);
PAINT ORANGE (-4695 2012);
FORCEPROP 1 LAST PART_NUMBER G21796-010
J 0
(-4660 1825);
DISPLAY 0.617021 (-4660 1825);
PAINT BLUE (-4660 1825);
FORCEPROP 1 LAST TOLERANCE 1%
J 0
(-4655 1975);
DISPLAY 0.617021 (-4655 1975);
PAINT SKYBLUE (-4655 1975);
FORCEPROP 1 LAST VALUE 100.0K
J 0
(-4655 2025);
DISPLAY 0.617021 (-4655 2025);
PAINT SKYBLUE (-4655 2025);
FORCEPROP 1 LAST LOCATION R25W142
J 0
(-4655 2075);
DISPLAY 0.617021 (-4655 2075);
PAINT AQUA (-4655 2075);
FORCEPROP 1 LAST PATH I156
J 0
(-4650 2125);
DISPLAY 0.978723 (-4650 2125);
PAINT WHITE (-4650 2125);
DISPLAY INVISIBLE (-4650 2125);
FORCEPROP 2 LAST SEC 1
J 0
(-4650 2175);
DISPLAY 0.680851 (-4650 2175);
PAINT MONO (-4650 2175);
DISPLAY INVISIBLE (-4650 2175);
FORCEPROP 2 LAST SEC_TYPE 0402
J 0
(-4650 2175);
DISPLAY 1.021277 (-4650 2175);
PAINT ORANGE (-4650 2175);
DISPLAY INVISIBLE (-4650 2175);
FORCEPROP 2 LAST CDS_LIB mstr_discrete
J 0
(-4700 1950);
PAINT ORANGE (-4700 1950);
DISPLAY INVISIBLE (-4700 1950);
FORCEPROP 2 LAST CDS_LOCATION R25W142
J 0
(-4655 2075);
DISPLAY 0.617021 (-4655 2075);
PAINT AQUA (-4655 2075);
DISPLAY INVISIBLE (-4655 2075);
FORCEADD GND..1
(-4700 1750);
FORCEPROP 3 LASTPIN (-4700 1800) SIG_NAME GND\g
J 0
(-4690 1810);
DISPLAY 0.659574 (-4690 1810);
PAINT MONO (-4690 1810);
DISPLAY INVISIBLE (-4690 1810);
FORCEPROP 1 LAST PATH I157
J 0
(-4625 1750);
DISPLAY 0.872340 (-4625 1750);
PAINT AQUA (-4625 1750);
DISPLAY INVISIBLE (-4625 1750);
FORCEPROP 2 LAST CDS_LIB mstr_symbols
J 0
(-4700 1750);
PAINT MONO (-4700 1750);
DISPLAY INVISIBLE (-4700 1750);
FORCEPROP 1 LAST SIZE 1B
J 0
(-4625 1700);
DISPLAY 0.872340 (-4625 1700);
PAINT AQUA (-4625 1700);
DISPLAY INVISIBLE (-4625 1700);
FORCEPROP 1 LAST VOLTAGE 0.0V
J 0
(-4745 1707);
DISPLAY 0.340426 (-4745 1707);
PAINT SKYBLUE (-4745 1707);
DISPLAY INVISIBLE (-4745 1707);
FORCEPROP 1 LAST BODY_TYPE PLUMBING
J 0
(-4745 1707);
DISPLAY 0.340426 (-4745 1707);
PAINT GREEN (-4745 1707);
DISPLAY INVISIBLE (-4745 1707);
FORCEPROP 1 LAST HDL_POWER GND
J 0
(-4700 1900);
DISPLAY 0.872340 (-4700 1900);
PAINT GREEN (-4700 1900);
DISPLAY INVISIBLE (-4700 1900);
FORCEADD OFFPAGE..1
R 2
(2300 3400);
FORCEPROP 2 LAST $XR1 190 
J 0
(2606 3400);
DISPLAY 0.638298 (2606 3400);
PAINT MONO (2606 3400);
FORCEPROP 2 LAST $XR0 119 
J 0
(2486 3400);
DISPLAY 0.638298 (2486 3400);
PAINT MONO (2486 3400);
FORCEPROP 2 LAST ROOM BMC
J 2
(2550 3475);
DISPLAY 1.361702 (2550 3475);
PAINT ORANGE (2550 3475);
DISPLAY INVISIBLE (2550 3475);
FORCEPROP 2 LAST BOM_COST SM_CONTROLLER
J 2
(1850 3450);
PAINT MONO (1850 3450);
DISPLAY INVISIBLE (1850 3450);
FORCEPROP 2 LAST PATH I158
J 0
(2475 3475);
DISPLAY 1.021277 (2475 3475);
PAINT ORANGE (2475 3475);
DISPLAY INVISIBLE (2475 3475);
FORCEPROP 2 LAST CDS_LIB mstr_standard
J 0
(2300 3400);
PAINT MONO (2300 3400);
DISPLAY INVISIBLE (2300 3400);
FORCEPROP 1 LAST OFFPAGE TRUE
J 2
(1975 3275);
DISPLAY 0.872340 (1975 3275);
PAINT GREEN (1975 3275);
DISPLAY INVISIBLE (1975 3275);
FORCEPROP 1 LAST COMMENT_BODY TRUE
J 2
(2175 3300);
DISPLAY 0.872340 (2175 3300);
PAINT GREEN (2175 3300);
DISPLAY INVISIBLE (2175 3300);
FORCEADD RES..1
(1500 3400);
FORCEPROP 1 LAST LOCATION R25W143
J 0
(1400 3325);
DISPLAY 0.617021 (1400 3325);
PAINT AQUA (1400 3325);
FORCEPROP 1 LAST PACK_TYPE 0402
J 0
(1400 3025);
DISPLAY 0.617021 (1400 3025);
PAINT SKYBLUE (1400 3025);
FORCEPROP 1 LAST TOLERANCE 5%
J 0
(1400 3225);
DISPLAY 0.617021 (1400 3225);
PAINT SKYBLUE (1400 3225);
FORCEPROP 1 LAST WATTAGE 1/16W
J 0
(1400 3175);
DISPLAY 0.617021 (1400 3175);
PAINT SKYBLUE (1400 3175);
FORCEPROP 1 LAST PART_NUMBER G21497-005
J 0
(1400 3075);
DISPLAY 0.617021 (1400 3075);
PAINT BLUE (1400 3075);
FORCEPROP 1 LAST MATERIAL CHIP
J 0
(1400 3125);
DISPLAY 0.617021 (1400 3125);
PAINT SKYBLUE (1400 3125);
FORCEPROP 1 LAST VALUE 0.0
J 0
(1400 3275);
DISPLAY 0.617021 (1400 3275);
PAINT SKYBLUE (1400 3275);
FORCEPROP 1 LASTPIN (1400 3400) $PN 1
J 0
(1412 3412);
DISPLAY 0.787234 (1412 3412);
PAINT ORANGE (1412 3412);
FORCEPROP 1 LASTPIN (1600 3400) $PN 2
J 0
(1562 3412);
DISPLAY 0.787234 (1562 3412);
PAINT ORANGE (1562 3412);
FORCEPROP 2 LAST CDS_LIB mstr_discrete
J 0
(1500 3400);
PAINT MONO (1500 3400);
DISPLAY INVISIBLE (1500 3400);
FORCEPROP 1 LAST PATH I159
J 0
(1450 3550);
DISPLAY 0.978723 (1450 3550);
PAINT WHITE (1450 3550);
DISPLAY INVISIBLE (1450 3550);
FORCEPROP 0 LAST ROOM DEBUG
J 0
(1450 3600);
DISPLAY 1.021277 (1450 3600);
PAINT ORANGE (1450 3600);
DISPLAY INVISIBLE (1450 3600);
FORCEPROP 2 LAST SEC_TYPE 0402
J 0
(1450 3600);
DISPLAY 1.021277 (1450 3600);
PAINT ORANGE (1450 3600);
DISPLAY INVISIBLE (1450 3600);
FORCEPROP 2 LAST SEC 1
J 0
(1450 3600);
DISPLAY 0.680851 (1450 3600);
PAINT MONO (1450 3600);
DISPLAY INVISIBLE (1450 3600);
FORCEADD OFFPAGE..2
(1850 3750);
FORCEPROP 2 LAST $XR0 186 
J 0
(2039 3750);
DISPLAY 0.638298 (2039 3750);
PAINT MONO (2039 3750);
FORCEPROP 2 LAST CDS_LIB mstr_standard
J 0
(1850 3750);
PAINT ORANGE (1850 3750);
DISPLAY INVISIBLE (1850 3750);
FORCEPROP 2 LAST PATH I16
J 0
(2050 3800);
DISPLAY 1.021277 (2050 3800);
PAINT ORANGE (2050 3800);
DISPLAY INVISIBLE (2050 3800);
FORCEPROP 1 LAST OFFPAGE TRUE
J 0
(2175 3625);
DISPLAY 0.872340 (2175 3625);
PAINT GREEN (2175 3625);
DISPLAY INVISIBLE (2175 3625);
FORCEPROP 1 LAST COMMENT_BODY TRUE
J 0
(1805 3655);
DISPLAY 0.872340 (1805 3655);
PAINT GREEN (1805 3655);
DISPLAY INVISIBLE (1805 3655);
FORCEADD CAP_A..1
(1450 2150);
FORCEPROP 1 LAST LOCATION C25W9
J 0
(1500 2250);
DISPLAY 0.617021 (1500 2250);
PAINT AQUA (1500 2250);
FORCEPROP 1 LAST VALUE 0.1UF
J 0
(1500 2200);
DISPLAY 0.617021 (1500 2200);
PAINT SKYBLUE (1500 2200);
FORCEPROP 1 LAST VOLTAGE 16V
J 0
(1500 2150);
DISPLAY 0.617021 (1500 2150);
PAINT SKYBLUE (1500 2150);
FORCEPROP 1 LAST TOLERANCE 10%
J 0
(1500 2100);
DISPLAY 0.617021 (1500 2100);
PAINT SKYBLUE (1500 2100);
FORCEPROP 1 LASTPIN (1450 2050) $PN 2
J 0
(1460 2030);
DISPLAY 0.617021 (1460 2030);
PAINT MONO (1460 2030);
FORCEPROP 1 LAST MATERIAL X7R
J 0
(1500 2050);
DISPLAY 0.617021 (1500 2050);
PAINT SKYBLUE (1500 2050);
FORCEPROP 1 LAST PART_NUMBER A36096-030
J 0
(1500 2000);
DISPLAY 0.617021 (1500 2000);
PAINT BLUE (1500 2000);
FORCEPROP 1 LAST PACK_TYPE 0402V
J 0
(1500 1950);
DISPLAY 0.617021 (1500 1950);
PAINT SKYBLUE (1500 1950);
FORCEPROP 1 LASTPIN (1450 2250) $PN 1
J 0
(1460 2230);
DISPLAY 0.617021 (1460 2230);
PAINT MONO (1460 2230);
FORCEPROP 2 LAST CDS_LOCATION C25W9
J 0
(1500 2250);
DISPLAY 0.617021 (1500 2250);
PAINT AQUA (1500 2250);
DISPLAY INVISIBLE (1500 2250);
FORCEPROP 1 LAST PATH I160
J 0
(1500 2300);
DISPLAY 0.978723 (1500 2300);
PAINT WHITE (1500 2300);
DISPLAY INVISIBLE (1500 2300);
FORCEPROP 2 LAST SEC 1
J 0
(1500 2350);
DISPLAY 0.936170 (1500 2350);
PAINT MONO (1500 2350);
DISPLAY INVISIBLE (1500 2350);
FORCEPROP 2 LAST SEC_TYPE 0402V
J 0
(1500 2350);
PAINT MONO (1500 2350);
DISPLAY INVISIBLE (1500 2350);
FORCEPROP 2 LAST CDS_SEC 1
J 0
(1500 2300);
PAINT ORANGE (1500 2300);
DISPLAY INVISIBLE (1500 2300);
FORCEPROP 2 LAST CDS_LIB dev_discrete
J 0
(1450 2150);
PAINT ORANGE (1450 2150);
DISPLAY INVISIBLE (1450 2150);
FORCEPROP 2 LAST BOM_COST PROC_SIDEBAND
J 0
(1450 2150);
PAINT MONO (1450 2150);
DISPLAY INVISIBLE (1450 2150);
FORCEPROP 2 LAST ROOM PROC_SIDEBAND
J 0
(1500 1900);
DISPLAY 0.978723 (1500 1900);
PAINT ORANGE (1500 1900);
DISPLAY INVISIBLE (1500 1900);
FORCEADD CAP_A..1
R 1
(2000 2300);
FORCEPROP 1 LAST PACK_TYPE 0402V
J 0
(2250 2225);
DISPLAY 0.617021 (2250 2225);
PAINT SKYBLUE (2250 2225);
FORCEPROP 1 LAST LOCATION C25W7
J 0
(1800 2350);
DISPLAY 0.617021 (1800 2350);
PAINT AQUA (1800 2350);
FORCEPROP 1 LAST VALUE 0.1UF
J 0
(2000 2350);
DISPLAY 0.617021 (2000 2350);
PAINT SKYBLUE (2000 2350);
FORCEPROP 1 LAST VOLTAGE 16V
J 0
(2150 2350);
DISPLAY 0.617021 (2150 2350);
PAINT SKYBLUE (2150 2350);
FORCEPROP 1 LAST PART_NUMBER A36096-030
J 0
(2000 2225);
DISPLAY 0.617021 (2000 2225);
PAINT BLUE (2000 2225);
FORCEPROP 1 LAST TOLERANCE 10%
J 0
(1800 2225);
DISPLAY 0.617021 (1800 2225);
PAINT SKYBLUE (1800 2225);
FORCEPROP 1 LAST MATERIAL X7R
J 0
(1900 2225);
DISPLAY 0.617021 (1900 2225);
PAINT SKYBLUE (1900 2225);
FORCEPROP 1 LASTPIN (2100 2300) $PN 2
J 0
(2070 2310);
DISPLAY 0.617021 (2070 2310);
PAINT MONO (2070 2310);
FORCEPROP 1 LASTPIN (1900 2300) $PN 1
J 0
(1895 2310);
DISPLAY 0.617021 (1895 2310);
PAINT MONO (1895 2310);
FORCEPROP 2 LAST CDS_LOCATION C25W7
R 1
J 0
(1900 2350);
DISPLAY 0.617021 (1900 2350);
PAINT AQUA (1900 2350);
DISPLAY INVISIBLE (1900 2350);
FORCEPROP 2 LAST SEC 1
R 1
J 0
(1800 2350);
DISPLAY 0.936170 (1800 2350);
PAINT MONO (1800 2350);
DISPLAY INVISIBLE (1800 2350);
FORCEPROP 2 LAST SEC_TYPE 0402V
R 1
J 0
(1800 2350);
PAINT MONO (1800 2350);
DISPLAY INVISIBLE (1800 2350);
FORCEPROP 2 LAST CDS_SEC 1
R 1
J 0
(1850 2350);
PAINT ORANGE (1850 2350);
DISPLAY INVISIBLE (1850 2350);
FORCEPROP 2 LAST CDS_LIB dev_discrete
R 1
J 0
(2000 2300);
PAINT ORANGE (2000 2300);
DISPLAY INVISIBLE (2000 2300);
FORCEPROP 2 LAST BOM_COST PROC_SIDEBAND
R 1
J 0
(2000 2300);
PAINT MONO (2000 2300);
DISPLAY INVISIBLE (2000 2300);
FORCEPROP 2 LAST ROOM PROC_SIDEBAND
R 1
J 0
(2250 2350);
DISPLAY 0.978723 (2250 2350);
PAINT ORANGE (2250 2350);
DISPLAY INVISIBLE (2250 2350);
FORCEPROP 1 LAST PATH I161
R 1
J 0
(1850 2350);
DISPLAY 0.978723 (1850 2350);
PAINT WHITE (1850 2350);
DISPLAY INVISIBLE (1850 2350);
FORCEADD CAP_A..1
R 1
(2000 1950);
FORCEPROP 1 LAST PART_NUMBER A36096-030
J 0
(2000 1875);
DISPLAY 0.617021 (2000 1875);
PAINT BLUE (2000 1875);
FORCEPROP 1 LAST LOCATION C25W8
J 0
(1800 2000);
DISPLAY 0.617021 (1800 2000);
PAINT AQUA (1800 2000);
FORCEPROP 1 LAST VALUE 0.1UF
J 0
(2000 2000);
DISPLAY 0.617021 (2000 2000);
PAINT SKYBLUE (2000 2000);
FORCEPROP 1 LASTPIN (2100 1950) $PN 2
J 0
(2070 1960);
DISPLAY 0.617021 (2070 1960);
PAINT MONO (2070 1960);
FORCEPROP 1 LAST PACK_TYPE 0402V
J 0
(2250 1875);
DISPLAY 0.617021 (2250 1875);
PAINT SKYBLUE (2250 1875);
FORCEPROP 1 LAST VOLTAGE 16V
J 0
(2150 2000);
DISPLAY 0.617021 (2150 2000);
PAINT SKYBLUE (2150 2000);
FORCEPROP 1 LAST TOLERANCE 10%
J 0
(1800 1875);
DISPLAY 0.617021 (1800 1875);
PAINT SKYBLUE (1800 1875);
FORCEPROP 1 LAST MATERIAL X7R
J 0
(1900 1875);
DISPLAY 0.617021 (1900 1875);
PAINT SKYBLUE (1900 1875);
FORCEPROP 1 LASTPIN (1900 1950) $PN 1
J 0
(1895 1960);
DISPLAY 0.617021 (1895 1960);
PAINT MONO (1895 1960);
FORCEPROP 2 LAST CDS_LOCATION C25W8
R 1
J 0
(1900 2000);
DISPLAY 0.617021 (1900 2000);
PAINT AQUA (1900 2000);
DISPLAY INVISIBLE (1900 2000);
FORCEPROP 1 LAST PATH I162
R 1
J 0
(1850 2000);
DISPLAY 0.978723 (1850 2000);
PAINT WHITE (1850 2000);
DISPLAY INVISIBLE (1850 2000);
FORCEPROP 2 LAST SEC 1
R 1
J 0
(1800 2000);
DISPLAY 0.936170 (1800 2000);
PAINT MONO (1800 2000);
DISPLAY INVISIBLE (1800 2000);
FORCEPROP 2 LAST SEC_TYPE 0402V
R 1
J 0
(1800 2000);
PAINT MONO (1800 2000);
DISPLAY INVISIBLE (1800 2000);
FORCEPROP 2 LAST CDS_SEC 1
R 1
J 0
(1850 2000);
PAINT ORANGE (1850 2000);
DISPLAY INVISIBLE (1850 2000);
FORCEPROP 2 LAST CDS_LIB dev_discrete
R 1
J 0
(2000 1950);
PAINT ORANGE (2000 1950);
DISPLAY INVISIBLE (2000 1950);
FORCEPROP 2 LAST BOM_COST PROC_SIDEBAND
R 1
J 0
(2000 1950);
PAINT MONO (2000 1950);
DISPLAY INVISIBLE (2000 1950);
FORCEPROP 2 LAST ROOM PROC_SIDEBAND
R 1
J 0
(2250 2000);
DISPLAY 0.978723 (2250 2000);
PAINT ORANGE (2250 2000);
DISPLAY INVISIBLE (2250 2000);
FORCEADD OFFPAGE..1
R 2
(950 2500);
FORCEPROP 2 LAST $XR0 119 
J 0
(1136 2500);
DISPLAY 0.638298 (1136 2500);
PAINT MONO (1136 2500);
FORCEPROP 2 LAST PATH I163
J 0
(1150 2550);
DISPLAY 1.021277 (1150 2550);
PAINT ORANGE (1150 2550);
DISPLAY INVISIBLE (1150 2550);
FORCEPROP 2 LAST CDS_LIB mstr_standard
J 0
(950 2500);
PAINT MONO (950 2500);
DISPLAY INVISIBLE (950 2500);
FORCEPROP 1 LAST OFFPAGE TRUE
J 2
(625 2375);
DISPLAY 0.872340 (625 2375);
PAINT GREEN (625 2375);
DISPLAY INVISIBLE (625 2375);
FORCEPROP 1 LAST COMMENT_BODY TRUE
J 2
(825 2400);
DISPLAY 0.872340 (825 2400);
PAINT GREEN (825 2400);
DISPLAY INVISIBLE (825 2400);
FORCEADD RES..2
(-4750 1300);
FORCEPROP 1 LAST VALUE 100.0K
J 0
(-4705 1375);
DISPLAY 0.617021 (-4705 1375);
PAINT SKYBLUE (-4705 1375);
FORCEPROP 1 LAST TOLERANCE 1%
J 0
(-4705 1325);
DISPLAY 0.617021 (-4705 1325);
PAINT SKYBLUE (-4705 1325);
FORCEPROP 1 LAST WATTAGE 1/16W
J 0
(-4710 1275);
DISPLAY 0.617021 (-4710 1275);
PAINT SKYBLUE (-4710 1275);
FORCEPROP 1 LAST LOCATION R25W157
J 0
(-4705 1425);
DISPLAY 0.617021 (-4705 1425);
PAINT AQUA (-4705 1425);
FORCEPROP 1 LAST PACK_TYPE 0402
J 0
(-4710 1125);
DISPLAY 0.617021 (-4710 1125);
PAINT SKYBLUE (-4710 1125);
FORCEPROP 1 LAST PART_NUMBER G21796-010
J 0
(-4710 1175);
DISPLAY 0.617021 (-4710 1175);
PAINT BLUE (-4710 1175);
FORCEPROP 1 LAST MATERIAL CHIP
J 0
(-4710 1225);
DISPLAY 0.617021 (-4710 1225);
PAINT SKYBLUE (-4710 1225);
FORCEPROP 1 LASTPIN (-4750 1200) $PN 2
J 0
(-4745 1210);
DISPLAY 0.617021 (-4745 1210);
PAINT ORANGE (-4745 1210);
FORCEPROP 1 LASTPIN (-4750 1400) $PN 1
J 0
(-4745 1362);
DISPLAY 0.617021 (-4745 1362);
PAINT ORANGE (-4745 1362);
FORCEPROP 2 LAST CDS_LIB mstr_discrete
J 0
(-4750 1300);
PAINT ORANGE (-4750 1300);
DISPLAY INVISIBLE (-4750 1300);
FORCEPROP 2 LAST SEC_TYPE 0402
J 0
(-4700 1525);
DISPLAY 1.021277 (-4700 1525);
PAINT ORANGE (-4700 1525);
DISPLAY INVISIBLE (-4700 1525);
FORCEPROP 2 LAST SEC 1
J 0
(-4700 1525);
DISPLAY 0.680851 (-4700 1525);
PAINT MONO (-4700 1525);
DISPLAY INVISIBLE (-4700 1525);
FORCEPROP 1 LAST PATH I164
J 0
(-4700 1475);
DISPLAY 0.978723 (-4700 1475);
PAINT WHITE (-4700 1475);
DISPLAY INVISIBLE (-4700 1475);
FORCEPROP 2 LAST CDS_LOCATION R25W157
J 0
(-4705 1425);
DISPLAY 0.617021 (-4705 1425);
PAINT AQUA (-4705 1425);
DISPLAY INVISIBLE (-4705 1425);
FORCEADD GND..1
(-4750 1100);
FORCEPROP 3 LASTPIN (-4750 1150) SIG_NAME GND\g
J 0
(-4740 1160);
DISPLAY 0.659574 (-4740 1160);
PAINT MONO (-4740 1160);
DISPLAY INVISIBLE (-4740 1160);
FORCEPROP 1 LAST VOLTAGE 0.0V
J 0
(-4795 1057);
DISPLAY 0.340426 (-4795 1057);
PAINT SKYBLUE (-4795 1057);
DISPLAY INVISIBLE (-4795 1057);
FORCEPROP 1 LAST SIZE 1B
J 0
(-4675 1050);
DISPLAY 0.872340 (-4675 1050);
PAINT AQUA (-4675 1050);
DISPLAY INVISIBLE (-4675 1050);
FORCEPROP 2 LAST CDS_LIB mstr_symbols
J 0
(-4750 1100);
PAINT MONO (-4750 1100);
DISPLAY INVISIBLE (-4750 1100);
FORCEPROP 1 LAST PATH I165
J 0
(-4675 1100);
DISPLAY 0.872340 (-4675 1100);
PAINT AQUA (-4675 1100);
DISPLAY INVISIBLE (-4675 1100);
FORCEPROP 1 LAST BODY_TYPE PLUMBING
J 0
(-4795 1057);
DISPLAY 0.340426 (-4795 1057);
PAINT GREEN (-4795 1057);
DISPLAY INVISIBLE (-4795 1057);
FORCEPROP 1 LAST HDL_POWER GND
J 0
(-4750 1250);
DISPLAY 0.872340 (-4750 1250);
PAINT GREEN (-4750 1250);
DISPLAY INVISIBLE (-4750 1250);
FORCEADD OFFPAGE..1
(-4850 2550);
FORCEPROP 2 LAST $XR0 251 
J 0
(-5102 2550);
DISPLAY 0.638298 (-5102 2550);
PAINT MONO (-5102 2550);
FORCEPROP 2 LAST CDS_LIB mstr_standard
J 0
(-4850 2550);
PAINT ORANGE (-4850 2550);
DISPLAY INVISIBLE (-4850 2550);
FORCEPROP 2 LAST PATH I166
J 0
(-5100 2600);
DISPLAY 1.021277 (-5100 2600);
PAINT ORANGE (-5100 2600);
DISPLAY INVISIBLE (-5100 2600);
FORCEPROP 1 LAST OFFPAGE TRUE
J 0
(-4525 2425);
DISPLAY 0.872340 (-4525 2425);
PAINT GREEN (-4525 2425);
DISPLAY INVISIBLE (-4525 2425);
FORCEPROP 1 LAST COMMENT_BODY TRUE
J 0
(-4725 2450);
DISPLAY 0.872340 (-4725 2450);
PAINT GREEN (-4725 2450);
DISPLAY INVISIBLE (-4725 2450);
FORCEADD OFFPAGE..2
(1850 3800);
FORCEPROP 2 LAST $XR0 186 
J 0
(2039 3800);
DISPLAY 0.638298 (2039 3800);
PAINT MONO (2039 3800);
FORCEPROP 2 LAST CDS_LIB mstr_standard
J 0
(1850 3800);
PAINT ORANGE (1850 3800);
DISPLAY INVISIBLE (1850 3800);
FORCEPROP 2 LAST PATH I17
J 0
(2050 3850);
DISPLAY 1.021277 (2050 3850);
PAINT ORANGE (2050 3850);
DISPLAY INVISIBLE (2050 3850);
FORCEPROP 1 LAST OFFPAGE TRUE
J 0
(2175 3675);
DISPLAY 0.872340 (2175 3675);
PAINT GREEN (2175 3675);
DISPLAY INVISIBLE (2175 3675);
FORCEPROP 1 LAST COMMENT_BODY TRUE
J 0
(1805 3705);
DISPLAY 0.872340 (1805 3705);
PAINT GREEN (1805 3705);
DISPLAY INVISIBLE (1805 3705);
FORCEADD OFFPAGE..5
(-4100 3000);
FORCEPROP 2 LAST $XR0 254 
J 0
(-4355 3000);
DISPLAY 0.638298 (-4355 3000);
PAINT MONO (-4355 3000);
FORCEPROP 2 LAST CDS_LIB mstr_standard
J 0
(-4100 3000);
PAINT ORANGE (-4100 3000);
DISPLAY INVISIBLE (-4100 3000);
FORCEPROP 2 LAST PATH I171
J 0
(-4375 3050);
DISPLAY 1.021277 (-4375 3050);
PAINT ORANGE (-4375 3050);
DISPLAY INVISIBLE (-4375 3050);
FORCEPROP 1 LAST OFFPAGE TRUE
J 0
(-3775 2875);
DISPLAY 0.872340 (-3775 2875);
PAINT GREEN (-3775 2875);
DISPLAY INVISIBLE (-3775 2875);
FORCEPROP 1 LAST COMMENT_BODY TRUE
J 0
(-4000 2925);
DISPLAY 0.872340 (-4000 2925);
PAINT GREEN (-4000 2925);
DISPLAY INVISIBLE (-4000 2925);
FORCEADD OFFPAGE..5
(-4100 3050);
FORCEPROP 2 LAST $XR0 255 
J 0
(-4355 3050);
DISPLAY 0.638298 (-4355 3050);
PAINT MONO (-4355 3050);
FORCEPROP 2 LAST CDS_LIB mstr_standard
J 0
(-4100 3050);
PAINT ORANGE (-4100 3050);
DISPLAY INVISIBLE (-4100 3050);
FORCEPROP 2 LAST PATH I172
J 0
(-4375 3100);
DISPLAY 1.021277 (-4375 3100);
PAINT ORANGE (-4375 3100);
DISPLAY INVISIBLE (-4375 3100);
FORCEPROP 1 LAST OFFPAGE TRUE
J 0
(-3775 2925);
DISPLAY 0.872340 (-3775 2925);
PAINT GREEN (-3775 2925);
DISPLAY INVISIBLE (-3775 2925);
FORCEPROP 1 LAST COMMENT_BODY TRUE
J 0
(-4000 2975);
DISPLAY 0.872340 (-4000 2975);
PAINT GREEN (-4000 2975);
DISPLAY INVISIBLE (-4000 2975);
FORCEADD RES..1
(-4150 3100);
FORCEPROP 1 LAST PACK_TYPE 0402
J 0
(-4050 3250);
DISPLAY 0.617021 (-4050 3250);
PAINT SKYBLUE (-4050 3250);
FORCEPROP 1 LAST MATERIAL CHIP
J 0
(-4050 3200);
DISPLAY 0.617021 (-4050 3200);
PAINT SKYBLUE (-4050 3200);
FORCEPROP 1 LASTPIN (-4250 3100) $PN 1
J 0
(-4238 3112);
DISPLAY 0.787234 (-4238 3112);
PAINT ORANGE (-4238 3112);
FORCEPROP 1 LAST PART_NUMBER G21497-005
J 0
(-4200 3300);
DISPLAY 0.617021 (-4200 3300);
PAINT BLUE (-4200 3300);
FORCEPROP 1 LAST VALUE 0.0
J 2
(-4125 3250);
DISPLAY 0.617021 (-4125 3250);
PAINT SKYBLUE (-4125 3250);
FORCEPROP 1 LAST TOLERANCE 5%
J 0
(-4175 3200);
DISPLAY 0.617021 (-4175 3200);
PAINT SKYBLUE (-4175 3200);
FORCEPROP 1 LAST WATTAGE 1/16W
J 0
(-4200 3150);
DISPLAY 0.617021 (-4200 3150);
PAINT SKYBLUE (-4200 3150);
FORCEPROP 1 LASTPIN (-4050 3100) $PN 2
J 0
(-4088 3112);
DISPLAY 0.787234 (-4088 3112);
PAINT ORANGE (-4088 3112);
FORCEPROP 1 LAST LOCATION R25W181
J 0
(-4200 3350);
DISPLAY 0.617021 (-4200 3350);
PAINT AQUA (-4200 3350);
FORCEPROP 0 LAST CDS_SEC 1
J 0
(-4200 3400);
DISPLAY INVISIBLE (-4200 3400);
FORCEPROP 0 LAST CDS_LOCATION R25W181
J 0
(-4200 3400);
DISPLAY INVISIBLE (-4200 3400);
FORCEPROP 2 LAST CDS_LIB mstr_discrete
J 0
(-4150 3100);
PAINT MONO (-4150 3100);
DISPLAY INVISIBLE (-4150 3100);
FORCEPROP 0 LAST ROOM DEBUG
J 0
(-4200 3300);
DISPLAY 1.021277 (-4200 3300);
PAINT ORANGE (-4200 3300);
DISPLAY INVISIBLE (-4200 3300);
FORCEPROP 2 LAST SEC_TYPE 0402
J 0
(-4200 3300);
DISPLAY 1.021277 (-4200 3300);
PAINT ORANGE (-4200 3300);
DISPLAY INVISIBLE (-4200 3300);
FORCEPROP 2 LAST SEC 1
J 0
(-4200 3300);
DISPLAY 0.680851 (-4200 3300);
PAINT MONO (-4200 3300);
DISPLAY INVISIBLE (-4200 3300);
FORCEPROP 1 LAST PATH I173
J 0
(-4200 3250);
DISPLAY 0.978723 (-4200 3250);
PAINT WHITE (-4200 3250);
DISPLAY INVISIBLE (-4200 3250);
FORCEADD OFFPAGE..1
(-4700 3100);
FORCEPROP 2 LAST $XR3 118 
J 0
(-4982 3028);
DISPLAY 0.638298 (-4982 3028);
PAINT MONO (-4982 3028);
FORCEPROP 2 LAST $XR2 111 
J 0
(-5102 3064);
DISPLAY 0.638298 (-5102 3064);
PAINT MONO (-5102 3064);
FORCEPROP 2 LAST $XR1 192 
J 0
(-4982 3064);
DISPLAY 0.638298 (-4982 3064);
PAINT MONO (-4982 3064);
FORCEPROP 2 LAST $XR0 190 
J 0
(-4982 3100);
DISPLAY 0.638298 (-4982 3100);
PAINT MONO (-4982 3100);
FORCEPROP 2 LAST CDS_LIB mstr_standard
J 0
(-4700 3100);
PAINT MONO (-4700 3100);
DISPLAY INVISIBLE (-4700 3100);
FORCEPROP 2 LAST PATH I174
J 0
(-4950 3150);
DISPLAY 1.021277 (-4950 3150);
PAINT ORANGE (-4950 3150);
DISPLAY INVISIBLE (-4950 3150);
FORCEPROP 1 LAST OFFPAGE TRUE
J 0
(-4375 2975);
DISPLAY 0.872340 (-4375 2975);
PAINT GREEN (-4375 2975);
DISPLAY INVISIBLE (-4375 2975);
FORCEPROP 1 LAST COMMENT_BODY TRUE
J 0
(-4575 3000);
DISPLAY 0.872340 (-4575 3000);
PAINT GREEN (-4575 3000);
DISPLAY INVISIBLE (-4575 3000);
FORCEADD OFFPAGE..1
(-4100 2750);
FORCEPROP 2 LAST $XR1 120 
J 0
(-4502 2750);
DISPLAY 0.638298 (-4502 2750);
PAINT MONO (-4502 2750);
FORCEPROP 2 LAST $XR0 164 
J 0
(-4382 2750);
DISPLAY 0.638298 (-4382 2750);
PAINT MONO (-4382 2750);
FORCEPROP 2 LAST PATH I175
J 0
(-4350 2800);
DISPLAY 1.021277 (-4350 2800);
PAINT ORANGE (-4350 2800);
DISPLAY INVISIBLE (-4350 2800);
FORCEPROP 2 LAST CDS_LIB mstr_standard
J 0
(-4100 2750);
PAINT MONO (-4100 2750);
DISPLAY INVISIBLE (-4100 2750);
FORCEPROP 1 LAST OFFPAGE TRUE
J 0
(-3775 2625);
DISPLAY 0.872340 (-3775 2625);
PAINT GREEN (-3775 2625);
DISPLAY INVISIBLE (-3775 2625);
FORCEPROP 1 LAST COMMENT_BODY TRUE
J 0
(-3975 2650);
DISPLAY 0.872340 (-3975 2650);
PAINT GREEN (-3975 2650);
DISPLAY INVISIBLE (-3975 2650);
FORCEADD OFFPAGE..1
(-4100 2800);
FORCEPROP 2 LAST $XR1 120 
J 0
(-4502 2800);
DISPLAY 0.638298 (-4502 2800);
PAINT MONO (-4502 2800);
FORCEPROP 2 LAST $XR0 164 
J 0
(-4382 2800);
DISPLAY 0.638298 (-4382 2800);
PAINT MONO (-4382 2800);
FORCEPROP 2 LAST CDS_LIB mstr_standard
J 0
(-4100 2800);
PAINT MONO (-4100 2800);
DISPLAY INVISIBLE (-4100 2800);
FORCEPROP 2 LAST PATH I176
J 0
(-4350 2850);
DISPLAY 1.021277 (-4350 2850);
PAINT ORANGE (-4350 2850);
DISPLAY INVISIBLE (-4350 2850);
FORCEPROP 1 LAST OFFPAGE TRUE
J 0
(-3775 2675);
DISPLAY 0.872340 (-3775 2675);
PAINT GREEN (-3775 2675);
DISPLAY INVISIBLE (-3775 2675);
FORCEPROP 1 LAST COMMENT_BODY TRUE
J 0
(-3975 2700);
DISPLAY 0.872340 (-3975 2700);
PAINT GREEN (-3975 2700);
DISPLAY INVISIBLE (-3975 2700);
FORCEADD OFFPAGE..1
(-4100 2850);
FORCEPROP 2 LAST $XR1 120 
J 0
(-4502 2850);
DISPLAY 0.638298 (-4502 2850);
PAINT MONO (-4502 2850);
FORCEPROP 2 LAST $XR0 164 
J 0
(-4382 2850);
DISPLAY 0.638298 (-4382 2850);
PAINT MONO (-4382 2850);
FORCEPROP 2 LAST CDS_LIB mstr_standard
J 0
(-4100 2850);
PAINT MONO (-4100 2850);
DISPLAY INVISIBLE (-4100 2850);
FORCEPROP 2 LAST PATH I177
J 0
(-4350 2900);
DISPLAY 1.021277 (-4350 2900);
PAINT ORANGE (-4350 2900);
DISPLAY INVISIBLE (-4350 2900);
FORCEPROP 1 LAST OFFPAGE TRUE
J 0
(-3775 2725);
DISPLAY 0.872340 (-3775 2725);
PAINT GREEN (-3775 2725);
DISPLAY INVISIBLE (-3775 2725);
FORCEPROP 1 LAST COMMENT_BODY TRUE
J 0
(-3975 2750);
DISPLAY 0.872340 (-3975 2750);
PAINT GREEN (-3975 2750);
DISPLAY INVISIBLE (-3975 2750);
FORCEADD OFFPAGE..1
(-4100 2900);
FORCEPROP 2 LAST $XR1 120 
J 0
(-4502 2900);
DISPLAY 0.638298 (-4502 2900);
PAINT MONO (-4502 2900);
FORCEPROP 2 LAST $XR0 164 
J 0
(-4382 2900);
DISPLAY 0.638298 (-4382 2900);
PAINT MONO (-4382 2900);
FORCEPROP 2 LAST CDS_LIB mstr_standard
J 0
(-4100 2900);
PAINT MONO (-4100 2900);
DISPLAY INVISIBLE (-4100 2900);
FORCEPROP 2 LAST PATH I178
J 0
(-4350 2950);
DISPLAY 1.021277 (-4350 2950);
PAINT ORANGE (-4350 2950);
DISPLAY INVISIBLE (-4350 2950);
FORCEPROP 1 LAST OFFPAGE TRUE
J 0
(-3775 2775);
DISPLAY 0.872340 (-3775 2775);
PAINT GREEN (-3775 2775);
DISPLAY INVISIBLE (-3775 2775);
FORCEPROP 1 LAST COMMENT_BODY TRUE
J 0
(-3975 2800);
DISPLAY 0.872340 (-3975 2800);
PAINT GREEN (-3975 2800);
DISPLAY INVISIBLE (-3975 2800);
FORCEADD OFFPAGE..1
(-4100 2950);
FORCEPROP 2 LAST $XR1 120 
J 0
(-4502 2950);
DISPLAY 0.638298 (-4502 2950);
PAINT MONO (-4502 2950);
FORCEPROP 2 LAST $XR0 164 
J 0
(-4382 2950);
DISPLAY 0.638298 (-4382 2950);
PAINT MONO (-4382 2950);
FORCEPROP 2 LAST CDS_LIB mstr_standard
J 0
(-4100 2950);
PAINT MONO (-4100 2950);
DISPLAY INVISIBLE (-4100 2950);
FORCEPROP 2 LAST PATH I179
J 0
(-4350 3000);
DISPLAY 1.021277 (-4350 3000);
PAINT ORANGE (-4350 3000);
DISPLAY INVISIBLE (-4350 3000);
FORCEPROP 1 LAST OFFPAGE TRUE
J 0
(-3775 2825);
DISPLAY 0.872340 (-3775 2825);
PAINT GREEN (-3775 2825);
DISPLAY INVISIBLE (-3775 2825);
FORCEPROP 1 LAST COMMENT_BODY TRUE
J 0
(-3975 2850);
DISPLAY 0.872340 (-3975 2850);
PAINT GREEN (-3975 2850);
DISPLAY INVISIBLE (-3975 2850);
FORCEADD OFFPAGE..2
(1850 3700);
FORCEPROP 2 LAST $XR0 150 
J 0
(2039 3700);
DISPLAY 0.638298 (2039 3700);
PAINT MONO (2039 3700);
FORCEPROP 2 LAST CDS_LIB mstr_standard
J 0
(1850 3700);
PAINT ORANGE (1850 3700);
DISPLAY INVISIBLE (1850 3700);
FORCEPROP 2 LAST PATH I18
J 0
(2100 3750);
DISPLAY 1.021277 (2100 3750);
PAINT ORANGE (2100 3750);
DISPLAY INVISIBLE (2100 3750);
FORCEPROP 1 LAST OFFPAGE TRUE
J 0
(2175 3575);
DISPLAY 0.872340 (2175 3575);
PAINT GREEN (2175 3575);
DISPLAY INVISIBLE (2175 3575);
FORCEPROP 1 LAST COMMENT_BODY TRUE
J 0
(1805 3605);
DISPLAY 0.872340 (1805 3605);
PAINT GREEN (1805 3605);
DISPLAY INVISIBLE (1805 3605);
FORCEADD OFFPAGE..2
(1850 3650);
FORCEPROP 2 LAST $XR0 150 
J 0
(2039 3650);
DISPLAY 0.638298 (2039 3650);
PAINT MONO (2039 3650);
FORCEPROP 2 LAST CDS_LIB mstr_standard
J 0
(1850 3650);
PAINT ORANGE (1850 3650);
DISPLAY INVISIBLE (1850 3650);
FORCEPROP 2 LAST PATH I19
J 0
(2150 3700);
DISPLAY 1.021277 (2150 3700);
PAINT ORANGE (2150 3700);
DISPLAY INVISIBLE (2150 3700);
FORCEPROP 1 LAST OFFPAGE TRUE
J 0
(2175 3525);
DISPLAY 0.872340 (2175 3525);
PAINT GREEN (2175 3525);
DISPLAY INVISIBLE (2175 3525);
FORCEPROP 1 LAST COMMENT_BODY TRUE
J 0
(1805 3555);
DISPLAY 0.872340 (1805 3555);
PAINT GREEN (1805 3555);
DISPLAY INVISIBLE (1805 3555);
FORCEADD OFFPAGE..2
(2300 4400);
FORCEPROP 2 LAST $XR2 121 
J 0
(2489 4364);
DISPLAY 0.638298 (2489 4364);
PAINT MONO (2489 4364);
FORCEPROP 2 LAST $XR1 150 
J 0
(2609 4400);
DISPLAY 0.638298 (2609 4400);
PAINT MONO (2609 4400);
FORCEPROP 2 LAST $XR0 139 
J 0
(2489 4400);
DISPLAY 0.638298 (2489 4400);
PAINT MONO (2489 4400);
FORCEPROP 2 LAST PATH I2
J 0
(2625 4450);
DISPLAY 1.021277 (2625 4450);
PAINT ORANGE (2625 4450);
DISPLAY INVISIBLE (2625 4450);
FORCEPROP 2 LAST CDS_LIB mstr_standard
J 0
(2300 4400);
PAINT ORANGE (2300 4400);
DISPLAY INVISIBLE (2300 4400);
FORCEPROP 1 LAST OFFPAGE TRUE
J 0
(2625 4275);
DISPLAY 0.872340 (2625 4275);
PAINT GREEN (2625 4275);
DISPLAY INVISIBLE (2625 4275);
FORCEPROP 1 LAST COMMENT_BODY TRUE
J 0
(2255 4305);
DISPLAY 0.872340 (2255 4305);
PAINT GREEN (2255 4305);
DISPLAY INVISIBLE (2255 4305);
FORCEADD W_VCC_CIRCLE..1
(2450 2400);
FORCEPROP 3 LASTPIN (2450 2400) SIG_NAME VCC_ADCAV3V3\g
J 0
(2460 2410);
DISPLAY 0.659574 (2460 2410);
PAINT MONO (2460 2410);
DISPLAY INVISIBLE (2460 2410);
FORCEPROP 1 LAST HDL_POWER VCC_ADCAV3V3
J 1
(2471 2475);
DISPLAY 0.872340 (2471 2475);
PAINT ORANGE (2471 2475);
FORCEPROP 1 LAST PATH I20
J 0
(2450 2400);
DISPLAY 0.617021 (2450 2400);
PAINT GREEN (2450 2400);
DISPLAY INVISIBLE (2450 2400);
FORCEPROP 1 LAST CDS_LMAN_SYM_OUTLINE -100,100,100,-100
J 0
(2450 2400);
DISPLAY 0.468085 (2450 2400);
PAINT GREEN (2450 2400);
DISPLAY INVISIBLE (2450 2400);
FORCEPROP 2 LAST CDS_LIB w_power
J 0
(2450 2400);
PAINT MONO (2450 2400);
DISPLAY INVISIBLE (2450 2400);
FORCEPROP 1 LAST BODY_TYPE PLUMBING
J 0
(2462 2394);
DISPLAY 0.340426 (2462 2394);
PAINT GREEN (2462 2394);
DISPLAY INVISIBLE (2462 2394);
FORCEADD RES..1
(1000 4200);
FORCEPROP 1 LAST PACK_TYPE 0402
J 0
(1400 4250);
DISPLAY 0.638298 (1400 4250);
PAINT SKYBLUE (1400 4250);
FORCEPROP 1 LAST TOLERANCE 1.0%
J 2
(1325 4200);
DISPLAY 0.617021 (1325 4200);
PAINT SKYBLUE (1325 4200);
FORCEPROP 1 LAST PART_NUMBER G21796-250
J 0
(1100 4250);
DISPLAY 0.638298 (1100 4250);
PAINT BLUE (1100 4250);
FORCEPROP 1 LAST WATTAGE 1/16W
J 0
(725 4250);
DISPLAY 0.638298 (725 4250);
PAINT SKYBLUE (725 4250);
FORCEPROP 1 LASTPIN (900 4200) $PN 1
J 0
(912 4212);
DISPLAY 0.617021 (912 4212);
PAINT ORANGE (912 4212);
FORCEPROP 1 LAST MATERIAL CHIP
J 0
(875 4250);
DISPLAY 0.617021 (875 4250);
PAINT SKYBLUE (875 4250);
FORCEPROP 1 LASTPIN (1100 4200) $PN 2
J 0
(1062 4212);
DISPLAY 0.617021 (1062 4212);
PAINT ORANGE (1062 4212);
FORCEPROP 1 LAST VALUE 22.1
J 2
(1200 4200);
DISPLAY 0.617021 (1200 4200);
PAINT SKYBLUE (1200 4200);
FORCEPROP 1 LAST LOCATION R25W90
J 0
(750 4200);
DISPLAY 0.617021 (750 4200);
PAINT AQUA (750 4200);
FORCEPROP 2 LAST CDS_LOCATION R25W90
J 0
(950 4250);
DISPLAY 0.617021 (950 4250);
PAINT AQUA (950 4250);
DISPLAY INVISIBLE (950 4250);
FORCEPROP 0 LAST CDS_SEC 1
J 0
(950 4300);
PAINT MONO (950 4300);
DISPLAY INVISIBLE (950 4300);
FORCEPROP 2 LAST ROOM BMC
J 0
(950 4300);
DISPLAY 1.021277 (950 4300);
PAINT ORANGE (950 4300);
DISPLAY INVISIBLE (950 4300);
FORCEPROP 2 LAST BOM_COST SM_CONTROLLER
J 0
(950 4350);
DISPLAY 1.021277 (950 4350);
PAINT ORANGE (950 4350);
DISPLAY INVISIBLE (950 4350);
FORCEPROP 2 LAST SEC 1
J 0
(950 4400);
DISPLAY 0.680851 (950 4400);
PAINT MONO (950 4400);
DISPLAY INVISIBLE (950 4400);
FORCEPROP 2 LAST SEC_TYPE 0402
J 0
(950 4400);
DISPLAY 1.021277 (950 4400);
PAINT ORANGE (950 4400);
DISPLAY INVISIBLE (950 4400);
FORCEPROP 2 LAST CDS_LIB mstr_discrete
J 0
(1000 4200);
PAINT ORANGE (1000 4200);
DISPLAY INVISIBLE (1000 4200);
FORCEPROP 1 LAST PATH I21
J 0
(950 4350);
DISPLAY 0.978723 (950 4350);
PAINT WHITE (950 4350);
DISPLAY INVISIBLE (950 4350);
FORCEADD RES..1
(1000 4150);
FORCEPROP 1 LAST WATTAGE 1/16W
J 0
(725 4100);
DISPLAY 0.638298 (725 4100);
PAINT SKYBLUE (725 4100);
FORCEPROP 1 LAST LOCATION R25W89
J 0
(750 4150);
DISPLAY 0.617021 (750 4150);
PAINT AQUA (750 4150);
FORCEPROP 1 LAST PACK_TYPE 0402
J 0
(1400 4100);
DISPLAY 0.638298 (1400 4100);
PAINT SKYBLUE (1400 4100);
FORCEPROP 1 LAST PART_NUMBER G21796-250
J 0
(1100 4100);
DISPLAY 0.638298 (1100 4100);
PAINT BLUE (1100 4100);
FORCEPROP 1 LAST TOLERANCE 1.0%
J 2
(1325 4150);
DISPLAY 0.617021 (1325 4150);
PAINT SKYBLUE (1325 4150);
FORCEPROP 1 LAST MATERIAL CHIP
J 0
(875 4100);
DISPLAY 0.617021 (875 4100);
PAINT SKYBLUE (875 4100);
FORCEPROP 1 LASTPIN (900 4150) $PN 1
J 0
(912 4162);
DISPLAY 0.617021 (912 4162);
PAINT ORANGE (912 4162);
FORCEPROP 1 LASTPIN (1100 4150) $PN 2
J 0
(1062 4162);
DISPLAY 0.617021 (1062 4162);
PAINT ORANGE (1062 4162);
FORCEPROP 1 LAST VALUE 22.1
J 2
(1200 4150);
DISPLAY 0.617021 (1200 4150);
PAINT SKYBLUE (1200 4150);
FORCEPROP 2 LAST CDS_LOCATION R25W89
J 0
(950 4100);
DISPLAY 0.617021 (950 4100);
PAINT AQUA (950 4100);
DISPLAY INVISIBLE (950 4100);
FORCEPROP 0 LAST CDS_SEC 1
J 0
(1275 4150);
PAINT MONO (1275 4150);
DISPLAY INVISIBLE (1275 4150);
FORCEPROP 2 LAST SEC 1
J 0
(950 4350);
DISPLAY 0.680851 (950 4350);
PAINT MONO (950 4350);
DISPLAY INVISIBLE (950 4350);
FORCEPROP 2 LAST SEC_TYPE 0402
J 0
(950 4350);
DISPLAY 1.021277 (950 4350);
PAINT ORANGE (950 4350);
DISPLAY INVISIBLE (950 4350);
FORCEPROP 2 LAST CDS_LIB mstr_discrete
J 0
(1000 4150);
PAINT ORANGE (1000 4150);
DISPLAY INVISIBLE (1000 4150);
FORCEPROP 2 LAST ROOM BMC
J 0
(1275 4150);
DISPLAY 1.021277 (1275 4150);
PAINT ORANGE (1275 4150);
DISPLAY INVISIBLE (1275 4150);
FORCEPROP 2 LAST BOM_COST SM_CONTROLLER
J 0
(1275 4200);
DISPLAY 1.021277 (1275 4200);
PAINT ORANGE (1275 4200);
DISPLAY INVISIBLE (1275 4200);
FORCEPROP 1 LAST PATH I22
J 0
(950 4300);
DISPLAY 0.978723 (950 4300);
PAINT WHITE (950 4300);
DISPLAY INVISIBLE (950 4300);
FORCEADD RES..1
(800 4000);
FORCEPROP 1 LAST MATERIAL CHIP
J 0
(700 3950);
DISPLAY 0.617021 (700 3950);
PAINT SKYBLUE (700 3950);
FORCEPROP 1 LAST LOCATION R25W85
J 0
(550 4000);
DISPLAY 0.617021 (550 4000);
PAINT AQUA (550 4000);
FORCEPROP 1 LAST WATTAGE 1/16W
J 0
(525 3950);
DISPLAY 0.638298 (525 3950);
PAINT SKYBLUE (525 3950);
FORCEPROP 1 LAST TOLERANCE 1.0%
J 2
(1100 4000);
DISPLAY 0.617021 (1100 4000);
PAINT SKYBLUE (1100 4000);
FORCEPROP 1 LAST PART_NUMBER G21796-250
J 0
(850 3950);
DISPLAY 0.638298 (850 3950);
PAINT BLUE (850 3950);
FORCEPROP 1 LASTPIN (900 4000) $PN 2
J 0
(862 4012);
DISPLAY 0.617021 (862 4012);
PAINT ORANGE (862 4012);
FORCEPROP 1 LAST VALUE 22.1
J 0
(900 4000);
DISPLAY 0.617021 (900 4000);
PAINT SKYBLUE (900 4000);
FORCEPROP 1 LAST PACK_TYPE 0402
J 0
(1100 3950);
DISPLAY 0.638298 (1100 3950);
PAINT SKYBLUE (1100 3950);
FORCEPROP 1 LASTPIN (700 4000) $PN 1
J 0
(712 4012);
DISPLAY 0.617021 (712 4012);
PAINT ORANGE (712 4012);
FORCEPROP 0 LAST CDS_SEC 1
J 0
(1000 4000);
PAINT MONO (1000 4000);
DISPLAY INVISIBLE (1000 4000);
FORCEPROP 2 LAST ROOM BMC
J 0
(1000 4050);
DISPLAY 1.021277 (1000 4050);
PAINT ORANGE (1000 4050);
DISPLAY INVISIBLE (1000 4050);
FORCEPROP 2 LAST CDS_LIB mstr_discrete
J 0
(800 4000);
PAINT ORANGE (800 4000);
DISPLAY INVISIBLE (800 4000);
FORCEPROP 2 LAST SEC 1
J 0
(750 4200);
DISPLAY 0.680851 (750 4200);
PAINT MONO (750 4200);
DISPLAY INVISIBLE (750 4200);
FORCEPROP 2 LAST SEC_TYPE 0402
J 0
(750 4200);
DISPLAY 1.021277 (750 4200);
PAINT ORANGE (750 4200);
DISPLAY INVISIBLE (750 4200);
FORCEPROP 2 LAST BOM_COST SM_CONTROLLER
J 0
(1000 4100);
DISPLAY 1.021277 (1000 4100);
PAINT ORANGE (1000 4100);
DISPLAY INVISIBLE (1000 4100);
FORCEPROP 1 LAST PATH I23
J 0
(750 4150);
DISPLAY 0.978723 (750 4150);
PAINT WHITE (750 4150);
DISPLAY INVISIBLE (750 4150);
FORCEPROP 2 LAST CDS_LOCATION R25W85
J 0
(750 3950);
DISPLAY 0.617021 (750 3950);
PAINT AQUA (750 3950);
DISPLAY INVISIBLE (750 3950);
FORCEADD RES..1
(800 3750);
FORCEPROP 1 LAST WATTAGE 1/16W
J 0
(550 3700);
DISPLAY 0.638298 (550 3700);
PAINT SKYBLUE (550 3700);
FORCEPROP 1 LAST LOCATION R25W86
J 0
(550 3750);
DISPLAY 0.617021 (550 3750);
PAINT AQUA (550 3750);
FORCEPROP 1 LASTPIN (700 3750) $PN 1
J 0
(712 3762);
DISPLAY 0.617021 (712 3762);
PAINT ORANGE (712 3762);
FORCEPROP 1 LAST PART_NUMBER G21796-250
J 0
(875 3700);
DISPLAY 0.638298 (875 3700);
PAINT BLUE (875 3700);
FORCEPROP 1 LAST TOLERANCE 1.0%
J 2
(1100 3750);
DISPLAY 0.617021 (1100 3750);
PAINT SKYBLUE (1100 3750);
FORCEPROP 1 LAST PACK_TYPE 0402
J 0
(1125 3700);
DISPLAY 0.638298 (1125 3700);
PAINT SKYBLUE (1125 3700);
FORCEPROP 1 LAST MATERIAL CHIP
J 0
(725 3700);
DISPLAY 0.617021 (725 3700);
PAINT SKYBLUE (725 3700);
FORCEPROP 1 LAST VALUE 22.1
J 0
(900 3750);
DISPLAY 0.617021 (900 3750);
PAINT SKYBLUE (900 3750);
FORCEPROP 1 LASTPIN (900 3750) $PN 2
J 0
(862 3762);
DISPLAY 0.617021 (862 3762);
PAINT ORANGE (862 3762);
FORCEPROP 2 LAST CDS_LOCATION R25W86
J 0
(750 3700);
DISPLAY 0.617021 (750 3700);
PAINT AQUA (750 3700);
DISPLAY INVISIBLE (750 3700);
FORCEPROP 1 LAST PATH I24
J 0
(750 3900);
DISPLAY 0.978723 (750 3900);
PAINT WHITE (750 3900);
DISPLAY INVISIBLE (750 3900);
FORCEPROP 0 LAST CDS_SEC 1
J 0
(1000 3800);
PAINT MONO (1000 3800);
DISPLAY INVISIBLE (1000 3800);
FORCEPROP 2 LAST SEC 1
J 0
(750 3950);
DISPLAY 0.680851 (750 3950);
PAINT MONO (750 3950);
DISPLAY INVISIBLE (750 3950);
FORCEPROP 2 LAST SEC_TYPE 0402
J 0
(750 3950);
DISPLAY 1.021277 (750 3950);
PAINT ORANGE (750 3950);
DISPLAY INVISIBLE (750 3950);
FORCEPROP 2 LAST CDS_LIB mstr_discrete
J 0
(800 3750);
PAINT ORANGE (800 3750);
DISPLAY INVISIBLE (800 3750);
FORCEPROP 2 LAST ROOM BMC
J 0
(1000 3800);
DISPLAY 1.021277 (1000 3800);
PAINT ORANGE (1000 3800);
DISPLAY INVISIBLE (1000 3800);
FORCEPROP 2 LAST BOM_COST SM_CONTROLLER
J 0
(1000 3850);
DISPLAY 1.021277 (1000 3850);
PAINT ORANGE (1000 3850);
DISPLAY INVISIBLE (1000 3850);
FORCEADD RES..1
(800 3800);
FORCEPROP 1 LASTPIN (700 3800) $PN 1
J 0
(712 3812);
DISPLAY 0.617021 (712 3812);
PAINT ORANGE (712 3812);
FORCEPROP 1 LAST MATERIAL CHIP
J 0
(725 3850);
DISPLAY 0.617021 (725 3850);
PAINT SKYBLUE (725 3850);
FORCEPROP 1 LAST PART_NUMBER G21796-250
J 0
(875 3850);
DISPLAY 0.638298 (875 3850);
PAINT BLUE (875 3850);
FORCEPROP 1 LAST WATTAGE 1/16W
J 0
(550 3850);
DISPLAY 0.638298 (550 3850);
PAINT SKYBLUE (550 3850);
FORCEPROP 1 LAST TOLERANCE 1.0%
J 2
(1100 3800);
DISPLAY 0.617021 (1100 3800);
PAINT SKYBLUE (1100 3800);
FORCEPROP 1 LAST PACK_TYPE 0402
J 0
(1125 3850);
DISPLAY 0.638298 (1125 3850);
PAINT SKYBLUE (1125 3850);
FORCEPROP 1 LAST VALUE 22.1
J 0
(900 3800);
DISPLAY 0.617021 (900 3800);
PAINT SKYBLUE (900 3800);
FORCEPROP 1 LASTPIN (900 3800) $PN 2
J 0
(862 3812);
DISPLAY 0.617021 (862 3812);
PAINT ORANGE (862 3812);
FORCEPROP 1 LAST LOCATION R25W87
J 0
(550 3800);
DISPLAY 0.617021 (550 3800);
PAINT AQUA (550 3800);
FORCEPROP 0 LAST CDS_SEC 1
J 0
(1150 3900);
PAINT MONO (1150 3900);
DISPLAY INVISIBLE (1150 3900);
FORCEPROP 2 LAST ROOM BMC
J 0
(750 3900);
DISPLAY 1.021277 (750 3900);
PAINT ORANGE (750 3900);
DISPLAY INVISIBLE (750 3900);
FORCEPROP 2 LAST BOM_COST SM_CONTROLLER
J 0
(750 3950);
DISPLAY 1.021277 (750 3950);
PAINT ORANGE (750 3950);
DISPLAY INVISIBLE (750 3950);
FORCEPROP 2 LAST SEC 1
J 0
(750 4000);
DISPLAY 0.680851 (750 4000);
PAINT MONO (750 4000);
DISPLAY INVISIBLE (750 4000);
FORCEPROP 2 LAST SEC_TYPE 0402
J 0
(750 4000);
DISPLAY 1.021277 (750 4000);
PAINT ORANGE (750 4000);
DISPLAY INVISIBLE (750 4000);
FORCEPROP 2 LAST CDS_LIB mstr_discrete
J 0
(800 3800);
PAINT ORANGE (800 3800);
DISPLAY INVISIBLE (800 3800);
FORCEPROP 1 LAST PATH I25
J 0
(750 3950);
DISPLAY 0.978723 (750 3950);
PAINT WHITE (750 3950);
DISPLAY INVISIBLE (750 3950);
FORCEPROP 2 LAST CDS_LOCATION R25W87
J 0
(750 3850);
DISPLAY 0.617021 (750 3850);
PAINT AQUA (750 3850);
DISPLAY INVISIBLE (750 3850);
FORCEADD OFFPAGE..2
(950 2400);
FORCEPROP 2 LAST $XR0 161 
J 0
(1139 2400);
DISPLAY 0.638298 (1139 2400);
PAINT MONO (1139 2400);
FORCEPROP 2 LAST PATH I34
J 0
(1275 2450);
DISPLAY 1.021277 (1275 2450);
PAINT ORANGE (1275 2450);
DISPLAY INVISIBLE (1275 2450);
FORCEPROP 2 LAST CDS_LIB mstr_standard
J 0
(950 2400);
PAINT ORANGE (950 2400);
DISPLAY INVISIBLE (950 2400);
FORCEPROP 1 LAST OFFPAGE TRUE
J 0
(1275 2275);
DISPLAY 0.872340 (1275 2275);
PAINT GREEN (1275 2275);
DISPLAY INVISIBLE (1275 2275);
FORCEPROP 1 LAST COMMENT_BODY TRUE
J 0
(905 2305);
DISPLAY 0.872340 (905 2305);
PAINT GREEN (905 2305);
DISPLAY INVISIBLE (905 2305);
FORCEADD OFFPAGE..2
(950 2450);
FORCEPROP 2 LAST $XR0 161 
J 0
(1139 2450);
DISPLAY 0.638298 (1139 2450);
PAINT MONO (1139 2450);
FORCEPROP 2 LAST CDS_LIB mstr_standard
J 0
(950 2450);
PAINT ORANGE (950 2450);
DISPLAY INVISIBLE (950 2450);
FORCEPROP 2 LAST PATH I35
J 0
(1275 2500);
DISPLAY 1.021277 (1275 2500);
PAINT ORANGE (1275 2500);
DISPLAY INVISIBLE (1275 2500);
FORCEPROP 1 LAST OFFPAGE TRUE
J 0
(1275 2325);
DISPLAY 0.872340 (1275 2325);
PAINT GREEN (1275 2325);
DISPLAY INVISIBLE (1275 2325);
FORCEPROP 1 LAST COMMENT_BODY TRUE
J 0
(905 2355);
DISPLAY 0.872340 (905 2355);
PAINT GREEN (905 2355);
DISPLAY INVISIBLE (905 2355);
FORCEADD GND..1
R 2
(2450 1800);
FORCEPROP 3 LASTPIN (2450 1850) SIG_NAME GND\g
J 0
(2460 1860);
DISPLAY 0.659574 (2460 1860);
PAINT MONO (2460 1860);
DISPLAY INVISIBLE (2460 1860);
FORCEPROP 1 LAST VOLTAGE 0.0V
J 2
(2495 1757);
DISPLAY 0.340426 (2495 1757);
PAINT GREEN (2495 1757);
DISPLAY INVISIBLE (2495 1757);
FORCEPROP 1 LAST SIZE 1B
J 2
(2375 1750);
DISPLAY 0.872340 (2375 1750);
PAINT AQUA (2375 1750);
DISPLAY INVISIBLE (2375 1750);
FORCEPROP 2 LAST CDS_LIB mstr_symbols
J 2
(2450 1800);
PAINT MONO (2450 1800);
DISPLAY INVISIBLE (2450 1800);
FORCEPROP 1 LAST PATH I37
J 2
(2375 1800);
DISPLAY 0.872340 (2375 1800);
PAINT AQUA (2375 1800);
DISPLAY INVISIBLE (2375 1800);
FORCEPROP 1 LAST BODY_TYPE PLUMBING
J 2
(2495 1757);
DISPLAY 0.340426 (2495 1757);
PAINT GREEN (2495 1757);
DISPLAY INVISIBLE (2495 1757);
FORCEPROP 1 LAST HDL_POWER GND
J 2
(2450 1950);
DISPLAY 0.872340 (2450 1950);
PAINT GREEN (2450 1950);
DISPLAY INVISIBLE (2450 1950);
FORCEADD GND..1
(900 1750);
FORCEPROP 3 LASTPIN (900 1800) SIG_NAME GND\g
J 0
(910 1810);
DISPLAY 0.659574 (910 1810);
PAINT MONO (910 1810);
DISPLAY INVISIBLE (910 1810);
FORCEPROP 2 LAST CDS_LIB mstr_symbols
J 0
(900 1750);
PAINT ORANGE (900 1750);
DISPLAY INVISIBLE (900 1750);
FORCEPROP 1 LAST PATH I41
J 0
(975 1750);
DISPLAY 0.872340 (975 1750);
PAINT AQUA (975 1750);
DISPLAY INVISIBLE (975 1750);
FORCEPROP 1 LAST VOLTAGE 0.0V
J 0
(855 1707);
DISPLAY 0.340426 (855 1707);
PAINT GREEN (855 1707);
DISPLAY INVISIBLE (855 1707);
FORCEPROP 1 LAST SIZE 1B
J 0
(975 1700);
DISPLAY 0.872340 (975 1700);
PAINT AQUA (975 1700);
DISPLAY INVISIBLE (975 1700);
FORCEPROP 1 LAST BODY_TYPE PLUMBING
J 0
(855 1707);
DISPLAY 0.340426 (855 1707);
PAINT GREEN (855 1707);
DISPLAY INVISIBLE (855 1707);
FORCEPROP 1 LAST HDL_POWER GND
J 0
(900 1900);
DISPLAY 0.872340 (900 1900);
PAINT GREEN (900 1900);
DISPLAY INVISIBLE (900 1900);
FORCEADD RES..2
(-3600 4950);
FORCEPROP 1 LAST LOCATION R25W79
J 0
(-3555 5075);
DISPLAY 0.617021 (-3555 5075);
PAINT AQUA (-3555 5075);
FORCEPROP 1 LAST VALUE 10.0K
J 0
(-3555 5025);
DISPLAY 0.617021 (-3555 5025);
PAINT SKYBLUE (-3555 5025);
FORCEPROP 1 LAST PART_NUMBER G21796-016
J 0
(-3560 4825);
DISPLAY 0.617021 (-3560 4825);
PAINT BLUE (-3560 4825);
FORCEPROP 1 LAST PACK_TYPE 0402
J 0
(-3560 4775);
DISPLAY 0.617021 (-3560 4775);
PAINT SKYBLUE (-3560 4775);
FORCEPROP 1 LASTPIN (-3600 4850) $PN 2
J 0
(-3595 4860);
DISPLAY 0.617021 (-3595 4860);
PAINT ORANGE (-3595 4860);
FORCEPROP 1 LASTPIN (-3600 5050) $PN 1
J 0
(-3595 5012);
DISPLAY 0.617021 (-3595 5012);
PAINT ORANGE (-3595 5012);
FORCEPROP 1 LAST WATTAGE 1/16W
J 0
(-3560 4925);
DISPLAY 0.617021 (-3560 4925);
PAINT SKYBLUE (-3560 4925);
FORCEPROP 1 LAST MATERIAL CHIP
J 0
(-3560 4875);
DISPLAY 0.617021 (-3560 4875);
PAINT SKYBLUE (-3560 4875);
FORCEPROP 1 LAST TOLERANCE 1%
J 0
(-3555 4975);
DISPLAY 0.617021 (-3555 4975);
PAINT SKYBLUE (-3555 4975);
FORCEPROP 2 LAST CDS_LIB mstr_discrete
J 0
(-3600 4950);
PAINT ORANGE (-3600 4950);
DISPLAY INVISIBLE (-3600 4950);
FORCEPROP 2 LAST BOM_COST SM_CONTROLLER
J 0
(-3550 5175);
DISPLAY 1.021277 (-3550 5175);
PAINT ORANGE (-3550 5175);
DISPLAY INVISIBLE (-3550 5175);
FORCEPROP 2 LAST SEC_TYPE 0402
J 0
(-3550 5175);
DISPLAY 1.021277 (-3550 5175);
PAINT ORANGE (-3550 5175);
DISPLAY INVISIBLE (-3550 5175);
FORCEPROP 2 LAST SEC 1
J 0
(-3550 5175);
DISPLAY 0.680851 (-3550 5175);
PAINT MONO (-3550 5175);
DISPLAY INVISIBLE (-3550 5175);
FORCEPROP 2 LAST ROOM BMC
J 0
(-3550 5125);
DISPLAY 1.021277 (-3550 5125);
PAINT ORANGE (-3550 5125);
DISPLAY INVISIBLE (-3550 5125);
FORCEPROP 1 LAST PATH I42
J 0
(-3550 5125);
DISPLAY 0.978723 (-3550 5125);
PAINT WHITE (-3550 5125);
DISPLAY INVISIBLE (-3550 5125);
FORCEPROP 2 LAST CDS_LOCATION R25W79
J 0
(-3555 5075);
DISPLAY 0.617021 (-3555 5075);
PAINT AQUA (-3555 5075);
DISPLAY INVISIBLE (-3555 5075);
FORCEADD RES..2
(-3900 4950);
FORCEPROP 1 LAST PACK_TYPE 0402
J 0
(-3860 4775);
DISPLAY 0.617021 (-3860 4775);
PAINT SKYBLUE (-3860 4775);
FORCEPROP 1 LAST LOCATION R25W80
J 0
(-3855 5075);
DISPLAY 0.617021 (-3855 5075);
PAINT AQUA (-3855 5075);
FORCEPROP 1 LAST WATTAGE 1/16W
J 0
(-3860 4925);
DISPLAY 0.617021 (-3860 4925);
PAINT SKYBLUE (-3860 4925);
FORCEPROP 1 LAST TOLERANCE 1%
J 0
(-3855 4975);
DISPLAY 0.617021 (-3855 4975);
PAINT SKYBLUE (-3855 4975);
FORCEPROP 1 LAST PART_NUMBER G21796-016
J 0
(-3860 4825);
DISPLAY 0.617021 (-3860 4825);
PAINT BLUE (-3860 4825);
FORCEPROP 1 LASTPIN (-3900 4850) $PN 2
J 0
(-3895 4860);
DISPLAY 0.617021 (-3895 4860);
PAINT ORANGE (-3895 4860);
FORCEPROP 1 LASTPIN (-3900 5050) $PN 1
J 0
(-3895 5012);
DISPLAY 0.617021 (-3895 5012);
PAINT ORANGE (-3895 5012);
FORCEPROP 1 LAST MATERIAL CHIP
J 0
(-3860 4875);
DISPLAY 0.617021 (-3860 4875);
PAINT SKYBLUE (-3860 4875);
FORCEPROP 1 LAST VALUE 10.0K
J 0
(-3855 5025);
DISPLAY 0.617021 (-3855 5025);
PAINT SKYBLUE (-3855 5025);
FORCEPROP 2 LAST CDS_LOCATION R25W80
J 0
(-3855 5075);
DISPLAY 0.617021 (-3855 5075);
PAINT AQUA (-3855 5075);
DISPLAY INVISIBLE (-3855 5075);
FORCEPROP 1 LAST PATH I43
J 0
(-3850 5125);
DISPLAY 0.978723 (-3850 5125);
PAINT WHITE (-3850 5125);
DISPLAY INVISIBLE (-3850 5125);
FORCEPROP 2 LAST ROOM BMC
J 0
(-3850 5125);
DISPLAY 1.021277 (-3850 5125);
PAINT ORANGE (-3850 5125);
DISPLAY INVISIBLE (-3850 5125);
FORCEPROP 2 LAST SEC 1
J 0
(-3850 5175);
DISPLAY 0.680851 (-3850 5175);
PAINT MONO (-3850 5175);
DISPLAY INVISIBLE (-3850 5175);
FORCEPROP 2 LAST SEC_TYPE 0402
J 0
(-3850 5175);
DISPLAY 1.021277 (-3850 5175);
PAINT ORANGE (-3850 5175);
DISPLAY INVISIBLE (-3850 5175);
FORCEPROP 2 LAST BOM_COST SM_CONTROLLER
J 0
(-3850 5175);
DISPLAY 1.021277 (-3850 5175);
PAINT ORANGE (-3850 5175);
DISPLAY INVISIBLE (-3850 5175);
FORCEPROP 2 LAST CDS_LIB mstr_discrete
J 0
(-3900 4950);
PAINT ORANGE (-3900 4950);
DISPLAY INVISIBLE (-3900 4950);
FORCEADD P3V3_STBY..1
(-3900 5250);
FORCEPROP 3 LASTPIN (-3900 5200) SIG_NAME P3V3_STBY\g
J 0
(-3890 5210);
DISPLAY 0.659574 (-3890 5210);
PAINT MONO (-3890 5210);
DISPLAY INVISIBLE (-3890 5210);
FORCEPROP 1 LAST PATH I44
J 0
(-3855 5252);
DISPLAY 0.340426 (-3855 5252);
PAINT GREEN (-3855 5252);
DISPLAY INVISIBLE (-3855 5252);
FORCEPROP 1 LAST VOLTAGE 3.3V
J 0
(-3945 5207);
DISPLAY 0.340426 (-3945 5207);
PAINT SKYBLUE (-3945 5207);
DISPLAY INVISIBLE (-3945 5207);
FORCEPROP 2 LAST CDS_LIB mstr_symbols
J 0
(-3900 5250);
PAINT ORANGE (-3900 5250);
DISPLAY INVISIBLE (-3900 5250);
FORCEPROP 1 LAST SIZE 1B
J 0
(-3855 5272);
DISPLAY 0.340426 (-3855 5272);
PAINT GREEN (-3855 5272);
DISPLAY INVISIBLE (-3855 5272);
FORCEPROP 1 LAST BODY_TYPE PLUMBING
J 0
(-3945 5207);
DISPLAY 0.340426 (-3945 5207);
PAINT GREEN (-3945 5207);
DISPLAY INVISIBLE (-3945 5207);
FORCEPROP 1 LAST HDL_POWER P3V3_STBY
J 0
(-4200 5125);
DISPLAY 0.872340 (-4200 5125);
PAINT ORANGE (-4200 5125);
DISPLAY INVISIBLE (-4200 5125);
FORCEADD OFFPAGE..1
(-4650 4200);
FORCEPROP 2 LAST $XR1 139 
J 0
(-5022 4200);
DISPLAY 0.638298 (-5022 4200);
PAINT MONO (-5022 4200);
FORCEPROP 2 LAST $XR0 121 
J 0
(-4902 4200);
DISPLAY 0.638298 (-4902 4200);
PAINT MONO (-4902 4200);
FORCEPROP 2 LAST CDS_LIB mstr_standard
J 0
(-4650 4200);
PAINT ORANGE (-4650 4200);
DISPLAY INVISIBLE (-4650 4200);
FORCEPROP 2 LAST PATH I47
J 0
(-4900 4250);
DISPLAY 1.021277 (-4900 4250);
PAINT ORANGE (-4900 4250);
DISPLAY INVISIBLE (-4900 4250);
FORCEPROP 1 LAST OFFPAGE TRUE
J 0
(-4325 4075);
DISPLAY 0.872340 (-4325 4075);
PAINT GREEN (-4325 4075);
DISPLAY INVISIBLE (-4325 4075);
FORCEPROP 1 LAST COMMENT_BODY TRUE
J 0
(-4525 4100);
DISPLAY 0.872340 (-4525 4100);
PAINT GREEN (-4525 4100);
DISPLAY INVISIBLE (-4525 4100);
FORCEADD OFFPAGE..1
(-4650 4150);
FORCEPROP 2 LAST $XR1 139 
J 0
(-5022 4150);
DISPLAY 0.638298 (-5022 4150);
PAINT MONO (-5022 4150);
FORCEPROP 2 LAST $XR0 121 
J 0
(-4902 4150);
DISPLAY 0.638298 (-4902 4150);
PAINT MONO (-4902 4150);
FORCEPROP 2 LAST CDS_LIB mstr_standard
J 0
(-4650 4150);
PAINT ORANGE (-4650 4150);
DISPLAY INVISIBLE (-4650 4150);
FORCEPROP 2 LAST PATH I48
J 0
(-4900 4200);
DISPLAY 1.021277 (-4900 4200);
PAINT ORANGE (-4900 4200);
DISPLAY INVISIBLE (-4900 4200);
FORCEPROP 1 LAST OFFPAGE TRUE
J 0
(-4325 4025);
DISPLAY 0.872340 (-4325 4025);
PAINT GREEN (-4325 4025);
DISPLAY INVISIBLE (-4325 4025);
FORCEPROP 1 LAST COMMENT_BODY TRUE
J 0
(-4525 4050);
DISPLAY 0.872340 (-4525 4050);
PAINT GREEN (-4525 4050);
DISPLAY INVISIBLE (-4525 4050);
FORCEADD OFFPAGE..1
(-4650 4250);
FORCEPROP 2 LAST $XR1 139 
J 0
(-5022 4250);
DISPLAY 0.638298 (-5022 4250);
PAINT MONO (-5022 4250);
FORCEPROP 2 LAST $XR0 121 
J 0
(-4902 4250);
DISPLAY 0.638298 (-4902 4250);
PAINT MONO (-4902 4250);
FORCEPROP 2 LAST CDS_LIB mstr_standard
J 0
(-4650 4250);
PAINT ORANGE (-4650 4250);
DISPLAY INVISIBLE (-4650 4250);
FORCEPROP 2 LAST PATH I49
J 0
(-4900 4300);
DISPLAY 1.021277 (-4900 4300);
PAINT ORANGE (-4900 4300);
DISPLAY INVISIBLE (-4900 4300);
FORCEPROP 1 LAST OFFPAGE TRUE
J 0
(-4325 4125);
DISPLAY 0.872340 (-4325 4125);
PAINT GREEN (-4325 4125);
DISPLAY INVISIBLE (-4325 4125);
FORCEPROP 1 LAST COMMENT_BODY TRUE
J 0
(-4525 4150);
DISPLAY 0.872340 (-4525 4150);
PAINT GREEN (-4525 4150);
DISPLAY INVISIBLE (-4525 4150);
FORCEADD OFFPAGE..1
(-4650 4300);
FORCEPROP 2 LAST $XR1 125 
J 0
(-5022 4300);
DISPLAY 0.638298 (-5022 4300);
PAINT MONO (-5022 4300);
FORCEPROP 2 LAST $XR0 121 
J 0
(-4902 4300);
DISPLAY 0.638298 (-4902 4300);
PAINT MONO (-4902 4300);
FORCEPROP 2 LAST CDS_LIB mstr_standard
J 0
(-4650 4300);
PAINT MONO (-4650 4300);
DISPLAY INVISIBLE (-4650 4300);
FORCEPROP 2 LAST PATH I50
J 0
(-4900 4350);
DISPLAY 1.021277 (-4900 4350);
PAINT ORANGE (-4900 4350);
DISPLAY INVISIBLE (-4900 4350);
FORCEPROP 1 LAST OFFPAGE TRUE
J 0
(-4325 4175);
DISPLAY 0.872340 (-4325 4175);
PAINT GREEN (-4325 4175);
DISPLAY INVISIBLE (-4325 4175);
FORCEPROP 1 LAST COMMENT_BODY TRUE
J 0
(-4525 4200);
DISPLAY 0.872340 (-4525 4200);
PAINT GREEN (-4525 4200);
DISPLAY INVISIBLE (-4525 4200);
FORCEADD OFFPAGE..1
(-4650 3900);
FORCEPROP 2 LAST $XR0 186 
J 0
(-4902 3900);
DISPLAY 0.638298 (-4902 3900);
PAINT MONO (-4902 3900);
FORCEPROP 2 LAST CDS_LIB mstr_standard
J 0
(-4650 3900);
PAINT ORANGE (-4650 3900);
DISPLAY INVISIBLE (-4650 3900);
FORCEPROP 2 LAST PATH I51
J 0
(-4900 3950);
DISPLAY 1.021277 (-4900 3950);
PAINT ORANGE (-4900 3950);
DISPLAY INVISIBLE (-4900 3950);
FORCEPROP 1 LAST OFFPAGE TRUE
J 0
(-4325 3775);
DISPLAY 0.872340 (-4325 3775);
PAINT GREEN (-4325 3775);
DISPLAY INVISIBLE (-4325 3775);
FORCEPROP 1 LAST COMMENT_BODY TRUE
J 0
(-4525 3800);
DISPLAY 0.872340 (-4525 3800);
PAINT GREEN (-4525 3800);
DISPLAY INVISIBLE (-4525 3800);
FORCEADD OFFPAGE..1
(-4650 3850);
FORCEPROP 2 LAST $XR0 186 
J 0
(-4902 3850);
DISPLAY 0.638298 (-4902 3850);
PAINT MONO (-4902 3850);
FORCEPROP 2 LAST CDS_LIB mstr_standard
J 0
(-4650 3850);
PAINT ORANGE (-4650 3850);
DISPLAY INVISIBLE (-4650 3850);
FORCEPROP 2 LAST PATH I54
J 0
(-4900 3900);
DISPLAY 1.021277 (-4900 3900);
PAINT ORANGE (-4900 3900);
DISPLAY INVISIBLE (-4900 3900);
FORCEPROP 1 LAST OFFPAGE TRUE
J 0
(-4325 3725);
DISPLAY 0.872340 (-4325 3725);
PAINT GREEN (-4325 3725);
DISPLAY INVISIBLE (-4325 3725);
FORCEPROP 1 LAST COMMENT_BODY TRUE
J 0
(-4525 3750);
DISPLAY 0.872340 (-4525 3750);
PAINT GREEN (-4525 3750);
DISPLAY INVISIBLE (-4525 3750);
FORCEADD OFFPAGE..1
(-4650 3750);
FORCEPROP 2 LAST $XR0 186 
J 0
(-4902 3750);
DISPLAY 0.638298 (-4902 3750);
PAINT MONO (-4902 3750);
FORCEPROP 2 LAST CDS_LIB mstr_standard
J 0
(-4650 3750);
PAINT ORANGE (-4650 3750);
DISPLAY INVISIBLE (-4650 3750);
FORCEPROP 2 LAST PATH I55
J 0
(-4900 3800);
DISPLAY 1.021277 (-4900 3800);
PAINT ORANGE (-4900 3800);
DISPLAY INVISIBLE (-4900 3800);
FORCEPROP 1 LAST OFFPAGE TRUE
J 0
(-4325 3625);
DISPLAY 0.872340 (-4325 3625);
PAINT GREEN (-4325 3625);
DISPLAY INVISIBLE (-4325 3625);
FORCEPROP 1 LAST COMMENT_BODY TRUE
J 0
(-4525 3650);
DISPLAY 0.872340 (-4525 3650);
PAINT GREEN (-4525 3650);
DISPLAY INVISIBLE (-4525 3650);
FORCEADD OFFPAGE..1
(-4650 3800);
FORCEPROP 2 LAST $XR0 186 
J 0
(-4902 3800);
DISPLAY 0.638298 (-4902 3800);
PAINT MONO (-4902 3800);
FORCEPROP 2 LAST CDS_LIB mstr_standard
J 0
(-4650 3800);
PAINT ORANGE (-4650 3800);
DISPLAY INVISIBLE (-4650 3800);
FORCEPROP 2 LAST PATH I56
J 0
(-4900 3850);
DISPLAY 1.021277 (-4900 3850);
PAINT ORANGE (-4900 3850);
DISPLAY INVISIBLE (-4900 3850);
FORCEPROP 1 LAST OFFPAGE TRUE
J 0
(-4325 3675);
DISPLAY 0.872340 (-4325 3675);
PAINT GREEN (-4325 3675);
DISPLAY INVISIBLE (-4325 3675);
FORCEPROP 1 LAST COMMENT_BODY TRUE
J 0
(-4525 3700);
DISPLAY 0.872340 (-4525 3700);
PAINT GREEN (-4525 3700);
DISPLAY INVISIBLE (-4525 3700);
FORCEADD OFFPAGE..1
(-4850 2350);
FORCEPROP 2 LAST $XR1 181 
J 0
(-5222 2350);
DISPLAY 0.638298 (-5222 2350);
PAINT MONO (-5222 2350);
FORCEPROP 2 LAST $XR0 161 
J 0
(-5102 2350);
DISPLAY 0.638298 (-5102 2350);
PAINT MONO (-5102 2350);
FORCEPROP 2 LAST PATH I57
J 0
(-5100 2400);
DISPLAY 1.021277 (-5100 2400);
PAINT ORANGE (-5100 2400);
DISPLAY INVISIBLE (-5100 2400);
FORCEPROP 2 LAST CDS_LIB mstr_standard
J 0
(-4850 2350);
PAINT ORANGE (-4850 2350);
DISPLAY INVISIBLE (-4850 2350);
FORCEPROP 1 LAST OFFPAGE TRUE
J 0
(-4525 2225);
DISPLAY 0.872340 (-4525 2225);
PAINT GREEN (-4525 2225);
DISPLAY INVISIBLE (-4525 2225);
FORCEPROP 1 LAST COMMENT_BODY TRUE
J 0
(-4725 2250);
DISPLAY 0.872340 (-4725 2250);
PAINT GREEN (-4725 2250);
DISPLAY INVISIBLE (-4725 2250);
FORCEADD OFFPAGE..1
(-4850 2400);
FORCEPROP 2 LAST $XR0 181 
J 0
(-5102 2400);
DISPLAY 0.638298 (-5102 2400);
PAINT MONO (-5102 2400);
FORCEPROP 2 LAST PATH I58
J 0
(-5100 2450);
DISPLAY 1.021277 (-5100 2450);
PAINT ORANGE (-5100 2450);
DISPLAY INVISIBLE (-5100 2450);
FORCEPROP 2 LAST CDS_LIB mstr_standard
J 0
(-4850 2400);
PAINT ORANGE (-4850 2400);
DISPLAY INVISIBLE (-4850 2400);
FORCEPROP 1 LAST OFFPAGE TRUE
J 0
(-4525 2275);
DISPLAY 0.872340 (-4525 2275);
PAINT GREEN (-4525 2275);
DISPLAY INVISIBLE (-4525 2275);
FORCEPROP 1 LAST COMMENT_BODY TRUE
J 0
(-4725 2300);
DISPLAY 0.872340 (-4725 2300);
PAINT GREEN (-4725 2300);
DISPLAY INVISIBLE (-4725 2300);
FORCEADD OFFPAGE..1
(-4850 2450);
FORCEPROP 2 LAST $XR1 181 
J 0
(-5222 2450);
DISPLAY 0.638298 (-5222 2450);
PAINT MONO (-5222 2450);
FORCEPROP 2 LAST $XR0 161 
J 0
(-5102 2450);
DISPLAY 0.638298 (-5102 2450);
PAINT MONO (-5102 2450);
FORCEPROP 2 LAST PATH I59
J 0
(-5100 2500);
DISPLAY 1.021277 (-5100 2500);
PAINT ORANGE (-5100 2500);
DISPLAY INVISIBLE (-5100 2500);
FORCEPROP 2 LAST CDS_LIB mstr_standard
J 0
(-4850 2450);
PAINT ORANGE (-4850 2450);
DISPLAY INVISIBLE (-4850 2450);
FORCEPROP 1 LAST OFFPAGE TRUE
J 0
(-4525 2325);
DISPLAY 0.872340 (-4525 2325);
PAINT GREEN (-4525 2325);
DISPLAY INVISIBLE (-4525 2325);
FORCEPROP 1 LAST COMMENT_BODY TRUE
J 0
(-4725 2350);
DISPLAY 0.872340 (-4725 2350);
PAINT GREEN (-4725 2350);
DISPLAY INVISIBLE (-4725 2350);
FORCEADD OFFPAGE..2
(2300 4050);
FORCEPROP 2 LAST $XR0 150 
J 0
(2489 4050);
DISPLAY 0.638298 (2489 4050);
PAINT MONO (2489 4050);
FORCEPROP 2 LAST CDS_LIB mstr_standard
J 0
(2300 4050);
PAINT MONO (2300 4050);
DISPLAY INVISIBLE (2300 4050);
FORCEPROP 2 LAST PATH I6
J 0
(2625 4100);
DISPLAY 1.021277 (2625 4100);
PAINT ORANGE (2625 4100);
DISPLAY INVISIBLE (2625 4100);
FORCEPROP 1 LAST OFFPAGE TRUE
J 0
(2625 3925);
DISPLAY 0.872340 (2625 3925);
PAINT GREEN (2625 3925);
DISPLAY INVISIBLE (2625 3925);
FORCEPROP 1 LAST COMMENT_BODY TRUE
J 0
(2255 3955);
DISPLAY 0.872340 (2255 3955);
PAINT GREEN (2255 3955);
DISPLAY INVISIBLE (2255 3955);
FORCEADD OFFPAGE..1
(-4850 2500);
FORCEPROP 2 LAST $XR0 181 
J 0
(-5102 2500);
DISPLAY 0.638298 (-5102 2500);
PAINT MONO (-5102 2500);
FORCEPROP 2 LAST CDS_LIB mstr_standard
J 0
(-4850 2500);
PAINT ORANGE (-4850 2500);
DISPLAY INVISIBLE (-4850 2500);
FORCEPROP 2 LAST PATH I60
J 0
(-5100 2550);
DISPLAY 1.021277 (-5100 2550);
PAINT ORANGE (-5100 2550);
DISPLAY INVISIBLE (-5100 2550);
FORCEPROP 1 LAST OFFPAGE TRUE
J 0
(-4525 2375);
DISPLAY 0.872340 (-4525 2375);
PAINT GREEN (-4525 2375);
DISPLAY INVISIBLE (-4525 2375);
FORCEPROP 1 LAST COMMENT_BODY TRUE
J 0
(-4725 2400);
DISPLAY 0.872340 (-4725 2400);
PAINT GREEN (-4725 2400);
DISPLAY INVISIBLE (-4725 2400);
FORCEADD RES..2
(-3500 1950);
FORCEPROP 1 LAST PART_NUMBER G21796-010
J 0
(-3460 1825);
DISPLAY 0.617021 (-3460 1825);
PAINT BLUE (-3460 1825);
FORCEPROP 1 LAST PACK_TYPE 0402
J 0
(-3460 1775);
DISPLAY 0.617021 (-3460 1775);
PAINT SKYBLUE (-3460 1775);
FORCEPROP 1 LASTPIN (-3500 1850) $PN 2
J 0
(-3495 1860);
DISPLAY 0.617021 (-3495 1860);
PAINT ORANGE (-3495 1860);
FORCEPROP 1 LAST WATTAGE 1/16W
J 0
(-3460 1925);
DISPLAY 0.617021 (-3460 1925);
PAINT SKYBLUE (-3460 1925);
FORCEPROP 1 LAST MATERIAL CHIP
J 0
(-3460 1875);
DISPLAY 0.617021 (-3460 1875);
PAINT SKYBLUE (-3460 1875);
FORCEPROP 1 LAST VALUE 100.0K
J 0
(-3455 2025);
DISPLAY 0.617021 (-3455 2025);
PAINT SKYBLUE (-3455 2025);
FORCEPROP 1 LAST LOCATION R1U1
J 0
(-3455 2075);
DISPLAY 0.617021 (-3455 2075);
PAINT AQUA (-3455 2075);
FORCEPROP 1 LAST TOLERANCE 1%
J 0
(-3455 1975);
DISPLAY 0.617021 (-3455 1975);
PAINT SKYBLUE (-3455 1975);
FORCEPROP 1 LASTPIN (-3500 2050) $PN 1
J 0
(-3495 2012);
DISPLAY 0.617021 (-3495 2012);
PAINT ORANGE (-3495 2012);
FORCEPROP 2 LAST CDS_LIB mstr_discrete
J 0
(-3500 1950);
PAINT ORANGE (-3500 1950);
DISPLAY INVISIBLE (-3500 1950);
FORCEPROP 2 LAST CDS_LOCATION R1U1
J 0
(-3455 2075);
DISPLAY 0.617021 (-3455 2075);
PAINT AQUA (-3455 2075);
DISPLAY INVISIBLE (-3455 2075);
FORCEPROP 2 LAST SEC 1
J 0
(-3450 2175);
DISPLAY 0.680851 (-3450 2175);
PAINT MONO (-3450 2175);
DISPLAY INVISIBLE (-3450 2175);
FORCEPROP 2 LAST SEC_TYPE 0402
J 0
(-3450 2175);
DISPLAY 1.021277 (-3450 2175);
PAINT ORANGE (-3450 2175);
DISPLAY INVISIBLE (-3450 2175);
FORCEPROP 1 LAST PATH I61
J 0
(-3450 2125);
DISPLAY 0.978723 (-3450 2125);
PAINT WHITE (-3450 2125);
DISPLAY INVISIBLE (-3450 2125);
FORCEADD RES..2
(-3800 1950);
FORCEPROP 1 LASTPIN (-3800 2050) $PN 1
J 0
(-3795 2012);
DISPLAY 0.617021 (-3795 2012);
PAINT ORANGE (-3795 2012);
FORCEPROP 1 LASTPIN (-3800 1850) $PN 2
J 0
(-3795 1860);
DISPLAY 0.617021 (-3795 1860);
PAINT ORANGE (-3795 1860);
FORCEPROP 1 LAST PACK_TYPE 0402
J 0
(-3760 1775);
DISPLAY 0.617021 (-3760 1775);
PAINT SKYBLUE (-3760 1775);
FORCEPROP 1 LAST PART_NUMBER G21796-010
J 0
(-3760 1825);
DISPLAY 0.617021 (-3760 1825);
PAINT BLUE (-3760 1825);
FORCEPROP 1 LAST VALUE 100.0K
J 0
(-3755 2025);
DISPLAY 0.617021 (-3755 2025);
PAINT SKYBLUE (-3755 2025);
FORCEPROP 1 LAST TOLERANCE 1%
J 0
(-3755 1975);
DISPLAY 0.617021 (-3755 1975);
PAINT SKYBLUE (-3755 1975);
FORCEPROP 1 LAST MATERIAL CHIP
J 0
(-3760 1875);
DISPLAY 0.617021 (-3760 1875);
PAINT SKYBLUE (-3760 1875);
FORCEPROP 1 LAST WATTAGE 1/16W
J 0
(-3760 1925);
DISPLAY 0.617021 (-3760 1925);
PAINT SKYBLUE (-3760 1925);
FORCEPROP 1 LAST LOCATION R1U2
J 0
(-3755 2075);
DISPLAY 0.617021 (-3755 2075);
PAINT AQUA (-3755 2075);
FORCEPROP 2 LAST CDS_LIB mstr_discrete
J 0
(-3800 1950);
PAINT ORANGE (-3800 1950);
DISPLAY INVISIBLE (-3800 1950);
FORCEPROP 2 LAST CDS_LOCATION R1U2
J 0
(-3755 2075);
DISPLAY 0.617021 (-3755 2075);
PAINT AQUA (-3755 2075);
DISPLAY INVISIBLE (-3755 2075);
FORCEPROP 2 LAST SEC_TYPE 0402
J 0
(-3750 2175);
DISPLAY 1.021277 (-3750 2175);
PAINT ORANGE (-3750 2175);
DISPLAY INVISIBLE (-3750 2175);
FORCEPROP 2 LAST SEC 1
J 0
(-3750 2175);
DISPLAY 0.680851 (-3750 2175);
PAINT MONO (-3750 2175);
DISPLAY INVISIBLE (-3750 2175);
FORCEPROP 1 LAST PATH I62
J 0
(-3750 2125);
DISPLAY 0.978723 (-3750 2125);
PAINT WHITE (-3750 2125);
DISPLAY INVISIBLE (-3750 2125);
FORCEADD GND..1
(-3500 1750);
FORCEPROP 3 LASTPIN (-3500 1800) SIG_NAME GND\g
J 0
(-3490 1810);
DISPLAY 0.659574 (-3490 1810);
PAINT MONO (-3490 1810);
DISPLAY INVISIBLE (-3490 1810);
FORCEPROP 1 LAST PATH I63
J 0
(-3425 1750);
DISPLAY 0.872340 (-3425 1750);
PAINT AQUA (-3425 1750);
DISPLAY INVISIBLE (-3425 1750);
FORCEPROP 1 LAST SIZE 1B
J 0
(-3425 1700);
DISPLAY 0.872340 (-3425 1700);
PAINT AQUA (-3425 1700);
DISPLAY INVISIBLE (-3425 1700);
FORCEPROP 1 LAST VOLTAGE 0.0V
J 0
(-3545 1707);
DISPLAY 0.340426 (-3545 1707);
PAINT SKYBLUE (-3545 1707);
DISPLAY INVISIBLE (-3545 1707);
FORCEPROP 2 LAST CDS_LIB mstr_symbols
J 0
(-3500 1750);
PAINT ORANGE (-3500 1750);
DISPLAY INVISIBLE (-3500 1750);
FORCEPROP 1 LAST BODY_TYPE PLUMBING
J 0
(-3545 1707);
DISPLAY 0.340426 (-3545 1707);
PAINT GREEN (-3545 1707);
DISPLAY INVISIBLE (-3545 1707);
FORCEPROP 1 LAST HDL_POWER GND
J 0
(-3500 1900);
DISPLAY 0.872340 (-3500 1900);
PAINT GREEN (-3500 1900);
DISPLAY INVISIBLE (-3500 1900);
FORCEADD GND..1
(-3800 1750);
FORCEPROP 3 LASTPIN (-3800 1800) SIG_NAME GND\g
J 0
(-3790 1810);
DISPLAY 0.659574 (-3790 1810);
PAINT MONO (-3790 1810);
DISPLAY INVISIBLE (-3790 1810);
FORCEPROP 1 LAST PATH I64
J 0
(-3725 1750);
DISPLAY 0.872340 (-3725 1750);
PAINT AQUA (-3725 1750);
DISPLAY INVISIBLE (-3725 1750);
FORCEPROP 1 LAST SIZE 1B
J 0
(-3725 1700);
DISPLAY 0.872340 (-3725 1700);
PAINT AQUA (-3725 1700);
DISPLAY INVISIBLE (-3725 1700);
FORCEPROP 2 LAST CDS_LIB mstr_symbols
J 0
(-3800 1750);
PAINT ORANGE (-3800 1750);
DISPLAY INVISIBLE (-3800 1750);
FORCEPROP 1 LAST VOLTAGE 0.0V
J 0
(-3845 1707);
DISPLAY 0.340426 (-3845 1707);
PAINT SKYBLUE (-3845 1707);
DISPLAY INVISIBLE (-3845 1707);
FORCEPROP 1 LAST BODY_TYPE PLUMBING
J 0
(-3845 1707);
DISPLAY 0.340426 (-3845 1707);
PAINT GREEN (-3845 1707);
DISPLAY INVISIBLE (-3845 1707);
FORCEPROP 1 LAST HDL_POWER GND
J 0
(-3800 1900);
DISPLAY 0.872340 (-3800 1900);
PAINT GREEN (-3800 1900);
DISPLAY INVISIBLE (-3800 1900);
FORCEADD RES..2
(-4100 1950);
FORCEPROP 1 LASTPIN (-4100 1850) $PN 2
J 0
(-4095 1860);
DISPLAY 0.617021 (-4095 1860);
PAINT ORANGE (-4095 1860);
FORCEPROP 1 LAST PACK_TYPE 0402
J 0
(-4060 1775);
DISPLAY 0.617021 (-4060 1775);
PAINT SKYBLUE (-4060 1775);
FORCEPROP 1 LAST TOLERANCE 1%
J 0
(-4055 1975);
DISPLAY 0.617021 (-4055 1975);
PAINT SKYBLUE (-4055 1975);
FORCEPROP 1 LAST MATERIAL CHIP
J 0
(-4060 1875);
DISPLAY 0.617021 (-4060 1875);
PAINT SKYBLUE (-4060 1875);
FORCEPROP 1 LAST PART_NUMBER G21796-010
J 0
(-4060 1825);
DISPLAY 0.617021 (-4060 1825);
PAINT BLUE (-4060 1825);
FORCEPROP 1 LAST WATTAGE 1/16W
J 0
(-4060 1925);
DISPLAY 0.617021 (-4060 1925);
PAINT SKYBLUE (-4060 1925);
FORCEPROP 1 LAST LOCATION R1U4
J 0
(-4055 2075);
DISPLAY 0.617021 (-4055 2075);
PAINT AQUA (-4055 2075);
FORCEPROP 1 LAST VALUE 100.0K
J 0
(-4055 2025);
DISPLAY 0.617021 (-4055 2025);
PAINT SKYBLUE (-4055 2025);
FORCEPROP 1 LASTPIN (-4100 2050) $PN 1
J 0
(-4095 2012);
DISPLAY 0.617021 (-4095 2012);
PAINT ORANGE (-4095 2012);
FORCEPROP 1 LAST PATH I65
J 0
(-4050 2125);
DISPLAY 0.978723 (-4050 2125);
PAINT WHITE (-4050 2125);
DISPLAY INVISIBLE (-4050 2125);
FORCEPROP 2 LAST CDS_LIB mstr_discrete
J 0
(-4100 1950);
PAINT ORANGE (-4100 1950);
DISPLAY INVISIBLE (-4100 1950);
FORCEPROP 2 LAST CDS_LOCATION R1U4
J 0
(-4055 2075);
DISPLAY 0.617021 (-4055 2075);
PAINT AQUA (-4055 2075);
DISPLAY INVISIBLE (-4055 2075);
FORCEPROP 2 LAST SEC 1
J 0
(-4050 2175);
DISPLAY 0.680851 (-4050 2175);
PAINT MONO (-4050 2175);
DISPLAY INVISIBLE (-4050 2175);
FORCEPROP 2 LAST SEC_TYPE 0402
J 0
(-4050 2175);
DISPLAY 1.021277 (-4050 2175);
PAINT ORANGE (-4050 2175);
DISPLAY INVISIBLE (-4050 2175);
FORCEADD RES..2
(-4400 1950);
FORCEPROP 1 LASTPIN (-4400 1850) $PN 2
J 0
(-4395 1860);
DISPLAY 0.617021 (-4395 1860);
PAINT ORANGE (-4395 1860);
FORCEPROP 1 LAST TOLERANCE 1%
J 0
(-4355 1975);
DISPLAY 0.617021 (-4355 1975);
PAINT SKYBLUE (-4355 1975);
FORCEPROP 1 LASTPIN (-4400 2050) $PN 1
J 0
(-4395 2012);
DISPLAY 0.617021 (-4395 2012);
PAINT ORANGE (-4395 2012);
FORCEPROP 1 LAST MATERIAL CHIP
J 0
(-4360 1875);
DISPLAY 0.617021 (-4360 1875);
PAINT SKYBLUE (-4360 1875);
FORCEPROP 1 LAST WATTAGE 1/16W
J 0
(-4360 1925);
DISPLAY 0.617021 (-4360 1925);
PAINT SKYBLUE (-4360 1925);
FORCEPROP 1 LAST PACK_TYPE 0402
J 0
(-4360 1775);
DISPLAY 0.617021 (-4360 1775);
PAINT SKYBLUE (-4360 1775);
FORCEPROP 1 LAST PART_NUMBER G21796-010
J 0
(-4360 1825);
DISPLAY 0.617021 (-4360 1825);
PAINT BLUE (-4360 1825);
FORCEPROP 1 LAST LOCATION R1U5
J 0
(-4355 2075);
DISPLAY 0.617021 (-4355 2075);
PAINT AQUA (-4355 2075);
FORCEPROP 1 LAST VALUE 100.0K
J 0
(-4355 2025);
DISPLAY 0.617021 (-4355 2025);
PAINT SKYBLUE (-4355 2025);
FORCEPROP 2 LAST CDS_LIB mstr_discrete
J 0
(-4400 1950);
PAINT ORANGE (-4400 1950);
DISPLAY INVISIBLE (-4400 1950);
FORCEPROP 2 LAST CDS_LOCATION R1U5
J 0
(-4355 2075);
DISPLAY 0.617021 (-4355 2075);
PAINT AQUA (-4355 2075);
DISPLAY INVISIBLE (-4355 2075);
FORCEPROP 2 LAST SEC_TYPE 0402
J 0
(-4350 2175);
DISPLAY 1.021277 (-4350 2175);
PAINT ORANGE (-4350 2175);
DISPLAY INVISIBLE (-4350 2175);
FORCEPROP 2 LAST SEC 1
J 0
(-4350 2175);
DISPLAY 0.680851 (-4350 2175);
PAINT MONO (-4350 2175);
DISPLAY INVISIBLE (-4350 2175);
FORCEPROP 1 LAST PATH I66
J 0
(-4350 2125);
DISPLAY 0.978723 (-4350 2125);
PAINT WHITE (-4350 2125);
DISPLAY INVISIBLE (-4350 2125);
FORCEADD GND..1
(-4100 1750);
FORCEPROP 3 LASTPIN (-4100 1800) SIG_NAME GND\g
J 0
(-4090 1810);
DISPLAY 0.659574 (-4090 1810);
PAINT MONO (-4090 1810);
DISPLAY INVISIBLE (-4090 1810);
FORCEPROP 1 LAST SIZE 1B
J 0
(-4025 1700);
DISPLAY 0.872340 (-4025 1700);
PAINT AQUA (-4025 1700);
DISPLAY INVISIBLE (-4025 1700);
FORCEPROP 1 LAST VOLTAGE 0.0V
J 0
(-4145 1707);
DISPLAY 0.340426 (-4145 1707);
PAINT SKYBLUE (-4145 1707);
DISPLAY INVISIBLE (-4145 1707);
FORCEPROP 2 LAST CDS_LIB mstr_symbols
J 0
(-4100 1750);
PAINT ORANGE (-4100 1750);
DISPLAY INVISIBLE (-4100 1750);
FORCEPROP 1 LAST PATH I67
J 0
(-4025 1750);
DISPLAY 0.872340 (-4025 1750);
PAINT AQUA (-4025 1750);
DISPLAY INVISIBLE (-4025 1750);
FORCEPROP 1 LAST BODY_TYPE PLUMBING
J 0
(-4145 1707);
DISPLAY 0.340426 (-4145 1707);
PAINT GREEN (-4145 1707);
DISPLAY INVISIBLE (-4145 1707);
FORCEPROP 1 LAST HDL_POWER GND
J 0
(-4100 1900);
DISPLAY 0.872340 (-4100 1900);
PAINT GREEN (-4100 1900);
DISPLAY INVISIBLE (-4100 1900);
FORCEADD GND..1
(-4400 1750);
FORCEPROP 3 LASTPIN (-4400 1800) SIG_NAME GND\g
J 0
(-4390 1810);
DISPLAY 0.659574 (-4390 1810);
PAINT MONO (-4390 1810);
DISPLAY INVISIBLE (-4390 1810);
FORCEPROP 1 LAST SIZE 1B
J 0
(-4325 1700);
DISPLAY 0.872340 (-4325 1700);
PAINT AQUA (-4325 1700);
DISPLAY INVISIBLE (-4325 1700);
FORCEPROP 1 LAST VOLTAGE 0.0V
J 0
(-4445 1707);
DISPLAY 0.340426 (-4445 1707);
PAINT SKYBLUE (-4445 1707);
DISPLAY INVISIBLE (-4445 1707);
FORCEPROP 1 LAST PATH I68
J 0
(-4325 1750);
DISPLAY 0.872340 (-4325 1750);
PAINT AQUA (-4325 1750);
DISPLAY INVISIBLE (-4325 1750);
FORCEPROP 2 LAST CDS_LIB mstr_symbols
J 0
(-4400 1750);
PAINT ORANGE (-4400 1750);
DISPLAY INVISIBLE (-4400 1750);
FORCEPROP 1 LAST BODY_TYPE PLUMBING
J 0
(-4445 1707);
DISPLAY 0.340426 (-4445 1707);
PAINT GREEN (-4445 1707);
DISPLAY INVISIBLE (-4445 1707);
FORCEPROP 1 LAST HDL_POWER GND
J 0
(-4400 1900);
DISPLAY 0.872340 (-4400 1900);
PAINT GREEN (-4400 1900);
DISPLAY INVISIBLE (-4400 1900);
FORCEADD OFFPAGE..2
(2300 4100);
FORCEPROP 2 LAST $XR0 150 
J 0
(2489 4100);
DISPLAY 0.638298 (2489 4100);
PAINT MONO (2489 4100);
FORCEPROP 2 LAST PATH I7
J 0
(2625 4150);
DISPLAY 1.021277 (2625 4150);
PAINT ORANGE (2625 4150);
DISPLAY INVISIBLE (2625 4150);
FORCEPROP 2 LAST CDS_LIB mstr_standard
J 0
(2300 4100);
PAINT MONO (2300 4100);
DISPLAY INVISIBLE (2300 4100);
FORCEPROP 1 LAST OFFPAGE TRUE
J 0
(2625 3975);
DISPLAY 0.872340 (2625 3975);
PAINT GREEN (2625 3975);
DISPLAY INVISIBLE (2625 3975);
FORCEPROP 1 LAST COMMENT_BODY TRUE
J 0
(2255 4005);
DISPLAY 0.872340 (2255 4005);
PAINT GREEN (2255 4005);
DISPLAY INVISIBLE (2255 4005);
FORCEADD RES..2
(-150 1950);
FORCEPROP 1 LAST PART_NUMBER G21796-016
J 0
(-110 1825);
DISPLAY 0.617021 (-110 1825);
PAINT BLUE (-110 1825);
FORCEPROP 1 LAST VALUE 10.0K
J 0
(-105 2025);
DISPLAY 0.617021 (-105 2025);
PAINT SKYBLUE (-105 2025);
FORCEPROP 1 LASTPIN (-150 2050) $PN 1
J 0
(-145 2012);
DISPLAY 0.787234 (-145 2012);
PAINT ORANGE (-145 2012);
FORCEPROP 1 LAST MATERIAL CHIP
J 0
(-110 1875);
DISPLAY 0.617021 (-110 1875);
PAINT SKYBLUE (-110 1875);
FORCEPROP 1 LAST LOCATION R2N13
J 0
(-105 2075);
DISPLAY 0.617021 (-105 2075);
PAINT AQUA (-105 2075);
FORCEPROP 1 LAST TOLERANCE 1%
J 0
(-105 1975);
DISPLAY 0.617021 (-105 1975);
PAINT SKYBLUE (-105 1975);
FORCEPROP 1 LAST PACK_TYPE 0402
J 0
(-110 1775);
DISPLAY 0.617021 (-110 1775);
PAINT SKYBLUE (-110 1775);
FORCEPROP 1 LASTPIN (-150 1850) $PN 2
J 0
(-145 1860);
DISPLAY 0.787234 (-145 1860);
PAINT ORANGE (-145 1860);
FORCEPROP 1 LAST WATTAGE 1/16W
J 0
(-110 1925);
DISPLAY 0.617021 (-110 1925);
PAINT SKYBLUE (-110 1925);
FORCEPROP 1 LAST PATH I75
J 0
(-100 2125);
DISPLAY 0.978723 (-100 2125);
PAINT WHITE (-100 2125);
DISPLAY INVISIBLE (-100 2125);
FORCEPROP 2 LAST CDS_LIB mstr_discrete
J 0
(-150 1950);
PAINT MONO (-150 1950);
DISPLAY INVISIBLE (-150 1950);
FORCEPROP 0 LAST ROOM BMC
J 0
(-100 2175);
DISPLAY 1.021277 (-100 2175);
PAINT ORANGE (-100 2175);
DISPLAY INVISIBLE (-100 2175);
FORCEPROP 0 LAST BOM_COST SM_CONTROLLER
J 0
(-100 2275);
DISPLAY 1.021277 (-100 2275);
PAINT ORANGE (-100 2275);
DISPLAY INVISIBLE (-100 2275);
FORCEPROP 0 LAST SEC 1
J 0
(-100 2125);
DISPLAY 0.680851 (-100 2125);
PAINT MONO (-100 2125);
DISPLAY INVISIBLE (-100 2125);
FORCEPROP 2 LAST SEC_TYPE 0402
J 0
(-100 2175);
DISPLAY 1.021277 (-100 2175);
PAINT ORANGE (-100 2175);
DISPLAY INVISIBLE (-100 2175);
FORCEADD GND..1
(-150 1750);
FORCEPROP 3 LASTPIN (-150 1800) SIG_NAME GND\g
J 0
(-140 1810);
DISPLAY 0.659574 (-140 1810);
PAINT MONO (-140 1810);
DISPLAY INVISIBLE (-140 1810);
FORCEPROP 2 LAST CDS_LIB mstr_symbols
J 0
(-150 1750);
PAINT MONO (-150 1750);
DISPLAY INVISIBLE (-150 1750);
FORCEPROP 1 LAST SIZE 1B
J 0
(-75 1700);
DISPLAY 0.872340 (-75 1700);
PAINT AQUA (-75 1700);
DISPLAY INVISIBLE (-75 1700);
FORCEPROP 1 LAST VOLTAGE 0.0V
J 0
(-195 1707);
DISPLAY 0.340426 (-195 1707);
PAINT GREEN (-195 1707);
DISPLAY INVISIBLE (-195 1707);
FORCEPROP 1 LAST PATH I76
J 0
(-75 1750);
DISPLAY 0.872340 (-75 1750);
PAINT AQUA (-75 1750);
DISPLAY INVISIBLE (-75 1750);
FORCEPROP 1 LAST BODY_TYPE PLUMBING
J 0
(-195 1707);
DISPLAY 0.340426 (-195 1707);
PAINT GREEN (-195 1707);
DISPLAY INVISIBLE (-195 1707);
FORCEPROP 1 LAST HDL_POWER GND
J 0
(-150 1900);
DISPLAY 0.872340 (-150 1900);
PAINT GREEN (-150 1900);
DISPLAY INVISIBLE (-150 1900);
FORCEADD OFFPAGE..2
(950 2550);
FORCEPROP 2 LAST $XR3 247 
J 0
(1469 2550);
DISPLAY 0.638298 (1469 2550);
PAINT MONO (1469 2550);
FORCEPROP 2 LAST $XR2 190 
J 0
(1349 2550);
DISPLAY 0.638298 (1349 2550);
PAINT MONO (1349 2550);
FORCEPROP 2 LAST $XR1 120 
J 0
(1229 2550);
DISPLAY 0.638298 (1229 2550);
PAINT MONO (1229 2550);
FORCEPROP 2 LAST $XR0 92 
J 0
(1139 2550);
DISPLAY 0.638298 (1139 2550);
PAINT MONO (1139 2550);
FORCEPROP 2 LAST CDS_LIB mstr_standard
J 0
(950 2550);
PAINT MONO (950 2550);
DISPLAY INVISIBLE (950 2550);
FORCEPROP 2 LAST PATH I79
J 0
(1125 2625);
DISPLAY 1.021277 (1125 2625);
PAINT ORANGE (1125 2625);
DISPLAY INVISIBLE (1125 2625);
FORCEPROP 1 LAST OFFPAGE TRUE
J 0
(1275 2425);
DISPLAY 0.872340 (1275 2425);
PAINT GREEN (1275 2425);
DISPLAY INVISIBLE (1275 2425);
FORCEPROP 1 LAST COMMENT_BODY TRUE
J 0
(905 2455);
DISPLAY 0.872340 (905 2455);
PAINT GREEN (905 2455);
DISPLAY INVISIBLE (905 2455);
FORCEADD RES..1
(1000 4400);
FORCEPROP 1 LAST PART_NUMBER G21796-250
J 0
(1100 4450);
DISPLAY 0.638298 (1100 4450);
PAINT BLUE (1100 4450);
FORCEPROP 1 LAST MATERIAL CHIP
J 0
(875 4450);
DISPLAY 0.617021 (875 4450);
PAINT SKYBLUE (875 4450);
FORCEPROP 1 LAST PACK_TYPE 0402
J 0
(1400 4450);
DISPLAY 0.638298 (1400 4450);
PAINT SKYBLUE (1400 4450);
FORCEPROP 1 LAST VALUE 22.1
J 0
(1125 4400);
DISPLAY 0.617021 (1125 4400);
PAINT SKYBLUE (1125 4400);
FORCEPROP 1 LAST WATTAGE 1/16W
J 0
(725 4450);
DISPLAY 0.638298 (725 4450);
PAINT SKYBLUE (725 4450);
FORCEPROP 1 LAST TOLERANCE 1.0%
J 2
(1325 4400);
DISPLAY 0.617021 (1325 4400);
PAINT SKYBLUE (1325 4400);
FORCEPROP 1 LASTPIN (1100 4400) $PN 2
J 0
(1062 4412);
DISPLAY 0.617021 (1062 4412);
PAINT ORANGE (1062 4412);
FORCEPROP 1 LAST LOCATION R25W88
J 0
(750 4400);
DISPLAY 0.617021 (750 4400);
PAINT AQUA (750 4400);
FORCEPROP 1 LASTPIN (900 4400) $PN 1
J 0
(912 4412);
DISPLAY 0.617021 (912 4412);
PAINT ORANGE (912 4412);
FORCEPROP 2 LAST CDS_LOCATION R25W88
J 0
(950 4350);
DISPLAY 0.617021 (950 4350);
PAINT AQUA (950 4350);
DISPLAY INVISIBLE (950 4350);
FORCEPROP 0 LAST CDS_SEC 1
J 0
(1150 4450);
PAINT MONO (1150 4450);
DISPLAY INVISIBLE (1150 4450);
FORCEPROP 2 LAST SEC 1
J 0
(950 4600);
DISPLAY 0.680851 (950 4600);
PAINT MONO (950 4600);
DISPLAY INVISIBLE (950 4600);
FORCEPROP 2 LAST SEC_TYPE 0402
J 0
(950 4600);
DISPLAY 1.021277 (950 4600);
PAINT ORANGE (950 4600);
DISPLAY INVISIBLE (950 4600);
FORCEPROP 2 LAST ROOM BMC
J 0
(1200 4450);
DISPLAY 1.021277 (1200 4450);
PAINT ORANGE (1200 4450);
DISPLAY INVISIBLE (1200 4450);
FORCEPROP 2 LAST CDS_LIB mstr_discrete
J 0
(1000 4400);
PAINT ORANGE (1000 4400);
DISPLAY INVISIBLE (1000 4400);
FORCEPROP 2 LAST BOM_COST SM_CONTROLLER
J 0
(1200 4500);
DISPLAY 1.021277 (1200 4500);
PAINT ORANGE (1200 4500);
DISPLAY INVISIBLE (1200 4500);
FORCEPROP 1 LAST PATH I8
J 0
(950 4550);
DISPLAY 0.978723 (950 4550);
PAINT WHITE (950 4550);
DISPLAY INVISIBLE (950 4550);
FORCEADD OFFPAGE..2
(950 2600);
FORCEPROP 2 LAST $XR1 154 
J 0
(1259 2600);
DISPLAY 0.638298 (1259 2600);
PAINT MONO (1259 2600);
FORCEPROP 2 LAST $XR0 120 
J 0
(1139 2600);
DISPLAY 0.638298 (1139 2600);
PAINT MONO (1139 2600);
FORCEPROP 2 LAST PATH I81
J 0
(1125 2675);
DISPLAY 1.021277 (1125 2675);
PAINT ORANGE (1125 2675);
DISPLAY INVISIBLE (1125 2675);
FORCEPROP 2 LAST CDS_LIB mstr_standard
J 0
(950 2600);
PAINT MONO (950 2600);
DISPLAY INVISIBLE (950 2600);
FORCEPROP 1 LAST OFFPAGE TRUE
J 0
(1275 2475);
DISPLAY 0.872340 (1275 2475);
PAINT GREEN (1275 2475);
DISPLAY INVISIBLE (1275 2475);
FORCEPROP 1 LAST COMMENT_BODY TRUE
J 0
(905 2505);
DISPLAY 0.872340 (905 2505);
PAINT GREEN (905 2505);
DISPLAY INVISIBLE (905 2505);
FORCEADD OFFPAGE..1
(-4100 2700);
FORCEPROP 2 LAST $XR2 119 
J 0
(-4622 2700);
DISPLAY 0.638298 (-4622 2700);
PAINT MONO (-4622 2700);
FORCEPROP 2 LAST $XR1 182 
J 0
(-4502 2700);
DISPLAY 0.638298 (-4502 2700);
PAINT MONO (-4502 2700);
FORCEPROP 2 LAST $XR0 133 
J 0
(-4382 2700);
DISPLAY 0.638298 (-4382 2700);
PAINT MONO (-4382 2700);
FORCEPROP 2 LAST PATH I88
J 0
(-4375 2750);
DISPLAY 1.021277 (-4375 2750);
PAINT ORANGE (-4375 2750);
DISPLAY INVISIBLE (-4375 2750);
FORCEPROP 2 LAST CDS_LIB mstr_standard
J 0
(-4100 2700);
PAINT MONO (-4100 2700);
DISPLAY INVISIBLE (-4100 2700);
FORCEPROP 1 LAST OFFPAGE TRUE
J 0
(-3775 2575);
DISPLAY 0.872340 (-3775 2575);
PAINT GREEN (-3775 2575);
DISPLAY INVISIBLE (-3775 2575);
FORCEPROP 1 LAST COMMENT_BODY TRUE
J 0
(-3975 2600);
DISPLAY 0.872340 (-3975 2600);
PAINT GREEN (-3975 2600);
DISPLAY INVISIBLE (-3975 2600);
FORCEADD OFFPAGE..1
(-4100 2650);
FORCEPROP 2 LAST $XR2 119 
J 0
(-4622 2650);
DISPLAY 0.638298 (-4622 2650);
PAINT MONO (-4622 2650);
FORCEPROP 2 LAST $XR1 182 
J 0
(-4502 2650);
DISPLAY 0.638298 (-4502 2650);
PAINT MONO (-4502 2650);
FORCEPROP 2 LAST $XR0 133 
J 0
(-4382 2650);
DISPLAY 0.638298 (-4382 2650);
PAINT MONO (-4382 2650);
FORCEPROP 2 LAST PATH I89
J 0
(-4350 2700);
DISPLAY 1.021277 (-4350 2700);
PAINT ORANGE (-4350 2700);
DISPLAY INVISIBLE (-4350 2700);
FORCEPROP 2 LAST CDS_LIB mstr_standard
J 0
(-4100 2650);
PAINT MONO (-4100 2650);
DISPLAY INVISIBLE (-4100 2650);
FORCEPROP 1 LAST OFFPAGE TRUE
J 0
(-3775 2525);
DISPLAY 0.872340 (-3775 2525);
PAINT GREEN (-3775 2525);
DISPLAY INVISIBLE (-3775 2525);
FORCEPROP 1 LAST COMMENT_BODY TRUE
J 0
(-3975 2550);
DISPLAY 0.872340 (-3975 2550);
PAINT GREEN (-3975 2550);
DISPLAY INVISIBLE (-3975 2550);
FORCEADD OFFPAGE..2
(2300 4300);
FORCEPROP 2 LAST $XR0 150 
J 0
(2489 4300);
DISPLAY 0.638298 (2489 4300);
PAINT MONO (2489 4300);
FORCEPROP 2 LAST PATH I9
J 0
(2500 4350);
DISPLAY 1.021277 (2500 4350);
PAINT ORANGE (2500 4350);
DISPLAY INVISIBLE (2500 4350);
FORCEPROP 2 LAST CDS_LIB mstr_standard
J 0
(2300 4300);
PAINT MONO (2300 4300);
DISPLAY INVISIBLE (2300 4300);
FORCEPROP 1 LAST OFFPAGE TRUE
J 0
(2625 4175);
DISPLAY 0.872340 (2625 4175);
PAINT GREEN (2625 4175);
DISPLAY INVISIBLE (2625 4175);
FORCEPROP 1 LAST COMMENT_BODY TRUE
J 0
(2255 4205);
DISPLAY 0.872340 (2255 4205);
PAINT GREEN (2255 4205);
DISPLAY INVISIBLE (2255 4205);
FORCEADD DNS..2
(-4095 1520);
PAINT RED (-4095 1520);
FORCEPROP 2 LAST CDS_LIB mstr_misc
J 0
(-4095 1520);
PAINT ORANGE (-4095 1520);
DISPLAY INVISIBLE (-4095 1520);
FORCEPROP 1 LAST COMMENT_BODY TRUE
R 1
J 0
(-4020 1295);
DISPLAY 0.872340 (-4020 1295);
PAINT GREEN (-4020 1295);
DISPLAY INVISIBLE (-4020 1295);
FORCEADD INTEL_CORP_BPAGE..1
(2750 500);
FORCEPROP 1 LAST CDS_CON_LAST_MODIFIED Fri Jun 16 17:48:55 2017
J 0
(1325 825);
DISPLAY 1.361702 (1325 825);
PAINT GREEN (1325 825);
DISPLAY INVISIBLE (1325 825);
FORCEPROP 2 LAST CUSTOM_TXT_CDS <XR_PAGE_TITLE>
J 0
(-5140 5750);
DISPLAY 0.638298 (-5140 5750);
PAINT PINK (-5140 5750);
DISPLAY INVISIBLE (-5140 5750);
FORCEPROP 2 LAST CUSTOM_TXT_CDS <CON_LAST_MODIFIED>
J 0
(-1250 600);
PAINT ORANGE (-1250 600);
FORCEPROP 2 LAST CUSTOM_TXT_CDS <CURRENT_DESIGN_SHEET> OF <TOTAL_DESIGN_SHEETS>
J 0
(2250 525);
PAINT ORANGE (2250 525);
FORCEPROP 1 LAST SCH_TITLE BMC (6 OF 7)
J 0
(-5200 550);
DISPLAY 1.212766 (-5200 550);
PAINT ORANGE (-5200 550);
FORCEPROP 2 LAST CDS_LIB mstr_symbols
J 0
(2750 500);
PAINT MONO (2750 500);
DISPLAY INVISIBLE (2750 500);
FORCEPROP 2 LAST PAGE_BORDER TRUE
J 0
(-5140 5750);
DISPLAY 0.851064 (-5140 5750);
PAINT PINK (-5140 5750);
DISPLAY INVISIBLE (-5140 5750);
FORCEPROP 1 LAST COMMENT_BODY TRUE
J 0
(2762 512);
DISPLAY 0.617021 (2762 512);
PAINT GREEN (2762 512);
DISPLAY INVISIBLE (2762 512);
FORCEPROP 2 LAST CDS_XR_PAGE_TITLE CR-147 : @BASEBOARD_FAB2_LIB.BASEBOARD_FAB2(SCH_1):PAGE147
J 0
(-5140 5750);
DISPLAY 0.638298 (-5140 5750);
PAINT PINK (-5140 5750);
DISPLAY INVISIBLE (-5140 5750);
FORCEADD CAD_NOTE..1
(850 5000);
FORCEPROP 0 LAST L2 NEAR BMC
J 0
(700 4850);
DISPLAY 0.808511 (700 4850);
PAINT ORANGE (700 4850);
FORCEPROP 0 LAST L1 PLACE THESE RESISTORS
J 0
(700 4900);
DISPLAY 0.808511 (700 4900);
PAINT ORANGE (700 4900);
FORCEPROP 2 LAST CDS_LIB mstr_symbols
J 0
(850 5000);
PAINT ORANGE (850 5000);
DISPLAY INVISIBLE (850 5000);
FORCEPROP 1 LAST COMMENT_BODY TRUE
J 0
(875 5100);
DISPLAY 0.978723 (875 5100);
PAINT ORANGE (875 5100);
DISPLAY INVISIBLE (875 5100);
WIRE 16 -1 (50 3350)(-150 3350);
WIRE 16 -1 (-150 3350)(-150 3300);
WIRE 16 -1 (-275 3350)(-150 3350);
WIRE 16 -1 (-150 3300)(-150 3250);
WIRE 16 -1 (-275 3300)(-150 3300);
WIRE 16 -1 (-150 3250)(-275 3250);
WIRE 16 -1 (-4700 1850)(-4700 1800);
WIRE 16 -1 (-4750 1200)(-4750 1150);
WIRE 16 -1 (2450 2400)(2450 2300);
WIRE 16 -1 (2100 2300)(2450 2300);
FORCEPROP 0 LAST CDS_PHYS_NET_NAME P3V3_STBY_BMC_ADCAV33
J 0
(2383 2387);
PAINT MONO (2383 2387);
DISPLAY INVISIBLE (2383 2387);
FORCEPROP 0 LAST VOLTAGE +3.3V
J 0
(2383 2340);
PAINT MONO (2383 2340);
DISPLAY INVISIBLE (2383 2340);
WIRE 16 -1 (2450 1850)(2450 1950);
WIRE 16 -1 (2100 1950)(2450 1950);
WIRE 16 -1 (900 1850)(900 1800);
WIRE 16 -1 (-3900 5150)(-3900 5200);
WIRE 16 -1 (-3600 5150)(-3900 5150);
WIRE 16 -1 (-3900 5050)(-3900 5150);
WIRE 16 -1 (-3600 5050)(-3600 5150);
WIRE 16 -1 (-3500 1800)(-3500 1850);
WIRE 16 -1 (-3800 1800)(-3800 1850);
WIRE 16 -1 (-4100 1800)(-4100 1850);
WIRE 16 -1 (-4400 1800)(-4400 1850);
WIRE 16 -1 (-150 1800)(-150 1850);
WIRE 16 -1 (500 3700)(1800 3700);
WIRE 16 -1 (500 3700)(500 3750);
WIRE 16 -1 (500 3750)(700 3750);
WIRE 16 -1 (-275 3750)(500 3750);
FORCEPROP 2 LAST SIG_NAME RMII_BMC_OCP_TXD0_R
J 0
(-135 3760);
DISPLAY 0.638298 (-135 3760);
PAINT ORANGE (-135 3760);
WIRE 16 -1 (-275 2900)(900 2900);
FORCEPROP 2 LAST SIG_NAME A_P5V_SCALED
J 0
(-135 2910);
DISPLAY 0.638298 (-135 2910);
PAINT ORANGE (-135 2910);
WIRE 16 -1 (1900 1950)(1450 1950);
WIRE 16 -1 (1450 2050)(1450 1950);
WIRE 16 -1 (1275 1950)(1450 1950);
WIRE 16 -1 (1275 2250)(1275 1950);
WIRE 16 -1 (-275 2250)(1275 2250);
FORCEPROP 0 LAST VOLTAGE +3.3V
J 0
(75 2325);
DISPLAY 1.021277 (75 2325);
PAINT SKYBLUE (75 2325);
DISPLAY INVISIBLE (75 2325);
FORCEPROP 2 LAST SIG_NAME P3V3_STBY_BMC_ADCVREFN
J 0
(-135 2260);
DISPLAY 0.638298 (-135 2260);
PAINT ORANGE (-135 2260);
FORCEPROP 2 LASTPROP $XRERR UNIQUE?
J 0
(-375 2260);
DISPLAY 0.638298 (-375 2260);
PAINT MONO (-375 2260);
DISPLAY INVISIBLE (-375 2260);
WIRE 16 -1 (-4600 4000)(-3375 4000);
FORCEPROP 0 LAST CDS_PHYS_NET_NAME FM_BMC_FAULT_LED_N
J 0
(-4585 4039);
PAINT MONO (-4585 4039);
DISPLAY INVISIBLE (-4585 4039);
FORCEPROP 2 LAST SIG_NAME FM_BMC_FAULT_LED_N
J 0
(-4535 4010);
DISPLAY 0.638298 (-4535 4010);
PAINT ORANGE (-4535 4010);
WIRE 16 -1 (-275 3000)(900 3000);
FORCEPROP 2 LAST SIG_NAME A_P1V05_STBY_PCH_SENSOR
J 0
(-135 3010);
DISPLAY 0.638298 (-135 3010);
PAINT ORANGE (-135 3010);
WIRE 3 682 (1400 2400)(1400 1800);
WIRE 3 682 (2400 2400)(1400 2400);
WIRE 3 682 (1400 1800)(2400 1800);
WIRE 3 682 (2400 1800)(2400 2400);
WIRE 16 -1 (-4000 1500)(-3150 1500);
FORCEPROP 0 LAST CDS_PHYS_NET_NAME FM_FLASH_DESC_OVERRIDE
J 0
(-3960 1539);
PAINT MONO (-3960 1539);
DISPLAY INVISIBLE (-3960 1539);
FORCEPROP 2 LAST SIG_NAME FM_FLASH_DESC_OVERRIDE
J 0
(-3835 1510);
DISPLAY 0.617021 (-3835 1510);
PAINT ORANGE (-3835 1510);
WIRE 3 682 (-4800 1050)(-4800 1550);
WIRE 3 682 (-4350 1050)(-4800 1050);
WIRE 3 682 (-4800 1550)(-4350 1550);
WIRE 3 682 (-4350 1550)(-4350 1050);
WIRE 16 -1 (900 4000)(1800 4000);
FORCEPROP 2 LAST SIG_NAME RMII_BMC_OCP_TXEN
J 0
(1165 4010);
DISPLAY 0.638298 (1165 4010);
PAINT ORANGE (1165 4010);
WIRE 16 -1 (2250 4200)(1100 4200);
FORCEPROP 2 LAST SIG_NAME RMII_BMC_PCH_SPRNGVLLE_TXD1
J 0
(1365 4210);
DISPLAY 0.638298 (1365 4210);
PAINT ORANGE (1365 4210);
WIRE 16 -1 (1100 4400)(2250 4400);
FORCEPROP 2 LAST SIG_NAME RMII_BMC_PCH_SPRNGVLLE_TXEN
J 0
(1365 4410);
DISPLAY 0.638298 (1365 4410);
PAINT ORANGE (1365 4410);
WIRE 3 682 (1700 4450)(1700 5050);
WIRE 3 682 (2450 4450)(1700 4450);
WIRE 3 682 (1700 5050)(2450 5050);
WIRE 3 682 (2450 5050)(2450 4450);
WIRE 3 682 (-4800 1700)(-4450 1700);
WIRE 3 682 (-4450 2150)(-4450 1700);
WIRE 3 682 (-4800 1700)(-4800 2150);
WIRE 3 682 (-4800 2150)(-4450 2150);
WIRE 3 682 (-2900 2600)(-2850 2600);
WIRE 3 682 (-2850 2600)(-2850 2550);
WIRE 3 682 (-2850 2550)(-2900 2550);
WIRE 3 682 (-2800 2550)(-2850 2550);
WIRE 3 682 (-3550 4600)(-3300 4600);
WIRE 3 682 (-3550 4750)(-3550 4600);
WIRE 3 682 (-3300 4600)(-3300 4750);
WIRE 3 682 (-3300 4750)(-3550 4750);
WIRE 16 -1 (900 2150)(-275 2150);
FORCEPROP 0 LAST CDS_PHYS_NET_NAME PD_ADCREXT
J 0
(-60 2189);
PAINT MONO (-60 2189);
DISPLAY INVISIBLE (-60 2189);
FORCEPROP 2 LAST SIG_NAME PD_ADCREXT
J 0
(-135 2160);
DISPLAY 0.638298 (-135 2160);
PAINT ORANGE (-135 2160);
FORCEPROP 2 LASTPROP $XRERR UNIQUE?
J 0
(-375 2160);
DISPLAY 0.638298 (-375 2160);
PAINT MONO (-375 2160);
DISPLAY INVISIBLE (-375 2160);
WIRE 16 -1 (900 2050)(900 2150);
WIRE 16 -1 (-275 4600)(900 4600);
FORCEPROP 2 LAST SIG_NAME FM_BB_BMC_MP_GPIO
J 0
(-135 4610);
DISPLAY 0.638298 (-135 4610);
PAINT ORANGE (-135 4610);
WIRE 16 -1 (-275 4650)(900 4650);
FORCEPROP 0 LAST CDS_PHYS_NET_NAME FM_BMC_CPLD_MP_RST_N
J 0
(550 4692);
PAINT MONO (550 4692);
DISPLAY INVISIBLE (550 4692);
FORCEPROP 2 LAST SIG_NAME FM_BMC_CPLD_MP_RST_N
J 0
(-135 4660);
DISPLAY 0.638298 (-135 4660);
PAINT ORANGE (-135 4660);
WIRE 16 -1 (-275 2700)(900 2700);
FORCEPROP 2 LAST SIG_NAME PUMP_PWM_OUT
J 0
(-135 2710);
DISPLAY 0.638298 (-135 2710);
PAINT ORANGE (-135 2710);
WIRE 16 -1 (-275 2750)(900 2750);
FORCEPROP 2 LAST SIG_NAME FM_PWRBRK_N
J 0
(-135 2760);
DISPLAY 0.638298 (-135 2760);
PAINT ORANGE (-135 2760);
WIRE 16 -1 (-275 2600)(900 2600);
FORCEPROP 2 LAST SIG_NAME FM_BACKUP_BIOS_SEL_N
J 0
(-135 2610);
DISPLAY 0.638298 (-135 2610);
PAINT ORANGE (-135 2610);
WIRE 16 -1 (-275 2650)(900 2650);
FORCEPROP 0 LAST CDS_PHYS_NET_NAME FM_BIOS_SPI_BMC_CTRL
J 0
(-235 2692);
PAINT MONO (-235 2692);
DISPLAY INVISIBLE (-235 2692);
FORCEPROP 2 LAST SIG_NAME FM_BIOS_SPI_BMC_CTRL
J 0
(-135 2660);
DISPLAY 0.638298 (-135 2660);
PAINT ORANGE (-135 2660);
WIRE 16 -1 (-275 2550)(900 2550);
FORCEPROP 2 LAST SIG_NAME FM_CPU_MSMI_LVT3_N
J 0
(-135 2560);
DISPLAY 0.638298 (-135 2560);
PAINT ORANGE (-135 2560);
WIRE 16 -1 (-275 2450)(900 2450);
FORCEPROP 2 LAST SIG_NAME FAN_PWM_OUT_SYS1
J 0
(-135 2460);
DISPLAY 0.638298 (-135 2460);
PAINT ORANGE (-135 2460);
WIRE 16 -1 (-275 2500)(-150 2500);
WIRE 16 -1 (900 2500)(-150 2500);
FORCEPROP 2 LAST SIG_NAME FM_BIOS_PREFRB2_GOOD
J 0
(-135 2510);
DISPLAY 0.638298 (-135 2510);
PAINT ORANGE (-135 2510);
WIRE 16 -1 (-150 2050)(-150 2500);
WIRE 16 -1 (-275 2400)(900 2400);
FORCEPROP 2 LAST SIG_NAME FAN_PWM_OUT_SYS0
J 0
(-135 2410);
DISPLAY 0.638298 (-135 2410);
PAINT ORANGE (-135 2410);
WIRE 16 -1 (-275 2300)(1450 2300);
FORCEPROP 0 LAST VOLTAGE +3.3V
J 0
(500 2350);
DISPLAY 1.021277 (500 2350);
PAINT SKYBLUE (500 2350);
DISPLAY INVISIBLE (500 2350);
FORCEPROP 2 LAST SIG_NAME P3V3_STBY_BMC_ADCVREFP
J 0
(-135 2310);
DISPLAY 0.638298 (-135 2310);
PAINT ORANGE (-135 2310);
FORCEPROP 2 LASTPROP $XRERR UNIQUE?
J 0
(-375 2310);
DISPLAY 0.638298 (-375 2310);
PAINT MONO (-375 2310);
DISPLAY INVISIBLE (-375 2310);
WIRE 16 -1 (1450 2250)(1450 2300);
WIRE 16 -1 (1900 2300)(1450 2300);
WIRE 16 -1 (-275 3550)(900 3550);
FORCEPROP 2 LAST SIG_NAME H_CPU1_MEMGHJ_MEMHOT_LVT3_BMC_N
J 0
(-135 3560);
DISPLAY 0.638298 (-135 3560);
PAINT ORANGE (-135 3560);
WIRE 16 -1 (900 3600)(-275 3600);
FORCEPROP 2 LAST SIG_NAME H_CPU1_MEMKLM_MEMHOT_LVT3_BMC_N
J 0
(-135 3610);
DISPLAY 0.638298 (-135 3610);
PAINT ORANGE (-135 3610);
WIRE 16 -1 (-275 3500)(900 3500);
FORCEPROP 2 LAST SIG_NAME H_CPU0_MEMDEF_MEMHOT_LVT3_BMC_N
J 0
(-135 3510);
DISPLAY 0.638298 (-135 3510);
PAINT ORANGE (-135 3510);
WIRE 16 -1 (-275 3450)(900 3450);
FORCEPROP 2 LAST SIG_NAME H_CPU0_MEMABC_MEMHOT_LVT3_BMC_N
J 0
(-135 3460);
DISPLAY 0.638298 (-135 3460);
PAINT ORANGE (-135 3460);
WIRE 16 -1 (-275 3150)(900 3150);
FORCEPROP 2 LAST SIG_NAME A_P5V_STBY_SCALED
J 0
(-135 3160);
DISPLAY 0.638298 (-135 3160);
PAINT ORANGE (-135 3160);
WIRE 16 -1 (-275 3050)(900 3050);
FORCEPROP 2 LAST SIG_NAME A_PVNN_STBY_PCH_SENSOR
J 0
(-135 3060);
DISPLAY 0.638298 (-135 3060);
PAINT ORANGE (-135 3060);
WIRE 16 -1 (-275 3100)(900 3100);
FORCEPROP 2 LAST SIG_NAME A_P3V3_STBY_SCALED
J 0
(-135 3110);
DISPLAY 0.638298 (-135 3110);
PAINT ORANGE (-135 3110);
WIRE 16 -1 (-275 2950)(900 2950);
FORCEPROP 2 LAST SIG_NAME A_P12V_STBY_SCALED
J 0
(-135 2960);
DISPLAY 0.638298 (-135 2960);
PAINT ORANGE (-135 2960);
WIRE 16 -1 (-275 2850)(900 2850);
FORCEPROP 2 LAST SIG_NAME A_P3V3_SCALED
J 0
(-135 2860);
DISPLAY 0.638298 (-135 2860);
PAINT ORANGE (-135 2860);
WIRE 16 -1 (-275 4400)(900 4400);
FORCEPROP 2 LAST SIG_NAME RMII_BMC_SPRNGVLLE_TXEN_R
J 0
(-135 4410);
DISPLAY 0.638298 (-135 4410);
PAINT ORANGE (-135 4410);
FORCEPROP 2 LASTPROP $XRERR UNIQUE?
J 0
(-375 4410);
DISPLAY 0.638298 (-375 4410);
PAINT MONO (-375 4410);
DISPLAY INVISIBLE (-375 4410);
WIRE 16 -1 (-275 4250)(2250 4250);
FORCEPROP 2 LAST SIG_NAME TP_RGMII2TXD2_GPIOU2
J 0
(-135 4260);
DISPLAY 0.638298 (-135 4260);
PAINT ORANGE (-135 4260);
WIRE 16 -1 (-275 4300)(2250 4300);
FORCEPROP 2 LAST SIG_NAME TP_RGMII2TXD3_GPIOU3
J 0
(-135 4310);
DISPLAY 0.638298 (-135 4310);
PAINT ORANGE (-135 4310);
WIRE 16 -1 (700 4100)(2250 4100);
WIRE 16 -1 (-275 4200)(700 4200);
FORCEPROP 2 LAST SIG_NAME RMII_BMC_PCH_SPRNGVLLE_TXD1_R
J 0
(-135 4210);
DISPLAY 0.638298 (-135 4210);
PAINT ORANGE (-135 4210);
WIRE 16 -1 (700 4100)(700 4200);
WIRE 16 -1 (900 4200)(700 4200);
WIRE 16 -1 (650 4050)(2250 4050);
WIRE 16 -1 (650 4150)(650 4050);
WIRE 16 -1 (650 4150)(900 4150);
WIRE 16 -1 (-275 4150)(650 4150);
FORCEPROP 2 LAST SIG_NAME RMII_BMC_PCH_SPRNGVLLE_TXD0_R
J 0
(-135 4160);
DISPLAY 0.638298 (-135 4160);
PAINT ORANGE (-135 4160);
WIRE 16 -1 (-275 4000)(700 4000);
FORCEPROP 2 LAST SIG_NAME RMII_BMC_OCP_TXEN_R
J 0
(-135 4010);
DISPLAY 0.638298 (-135 4010);
PAINT ORANGE (-135 4010);
FORCEPROP 2 LASTPROP $XRERR UNIQUE?
J 0
(-375 4010);
DISPLAY 0.638298 (-375 4010);
PAINT MONO (-375 4010);
DISPLAY INVISIBLE (-375 4010);
WIRE 16 -1 (-4600 4400)(-3375 4400);
FORCEPROP 0 LAST CDS_PHYS_NET_NAME FM_FAST_PROCHOT_EN_N
J 0
(-4300 4439);
PAINT MONO (-4300 4439);
DISPLAY INVISIBLE (-4300 4439);
FORCEPROP 2 LAST SIG_NAME FM_FAST_PROCHOT_EN_N
J 0
(-4535 4410);
DISPLAY 0.638298 (-4535 4410);
PAINT ORANGE (-4535 4410);
WIRE 16 -1 (-4600 3800)(-3375 3800);
FORCEPROP 2 LAST SIG_NAME RMII_BMC_OCP_RXD1
J 0
(-4535 3810);
DISPLAY 0.638298 (-4535 3810);
PAINT ORANGE (-4535 3810);
WIRE 16 -1 (-4600 4050)(-3375 4050);
FORCEPROP 0 LAST $PHYS_NET_NAME CLK_50M_CKMNG_BMC_1
J 0
(-4475 4139);
PAINT MONO (-4475 4139);
DISPLAY INVISIBLE (-4475 4139);
FORCEPROP 0 LAST CDS_PHYS_NET_NAME CLK_50M_CKMNG_BMC_1
J 0
(-4475 4092);
PAINT MONO (-4475 4092);
DISPLAY INVISIBLE (-4475 4092);
FORCEPROP 2 LAST SIG_NAME CLK_50M_CKMNG_BMC_1
J 0
(-4535 4060);
DISPLAY 0.638298 (-4535 4060);
PAINT ORANGE (-4535 4060);
WIRE 16 -1 (-3600 4150)(-3600 4850);
WIRE 16 -1 (-3375 4150)(-3600 4150);
WIRE 16 -1 (-4600 4150)(-3600 4150);
FORCEPROP 2 LAST SIG_NAME RMII_SPRNGVLLE_BMC_PCH_RXD0
J 0
(-4535 4160);
DISPLAY 0.638298 (-4535 4160);
PAINT ORANGE (-4535 4160);
WIRE 16 -1 (-4600 4200)(-3900 4200);
FORCEPROP 2 LAST SIG_NAME RMII_SPRNGVLLE_BMC_PCH_RXD1
J 0
(-4535 4210);
DISPLAY 0.638298 (-4535 4210);
PAINT ORANGE (-4535 4210);
WIRE 16 -1 (-3900 4850)(-3900 4200);
WIRE 16 -1 (-3375 4200)(-3900 4200);
WIRE 16 -1 (-4600 4250)(-3375 4250);
FORCEPROP 2 LAST SIG_NAME RMII_BMC_PCH_SPRNGVLLE_CRSDV
J 0
(-4535 4260);
DISPLAY 0.638298 (-4535 4260);
PAINT ORANGE (-4535 4260);
WIRE 16 -1 (-4600 4300)(-3375 4300);
FORCEPROP 2 LAST SIG_NAME RMII_BMC_PCH_SPRNGVLLE_RXER
J 0
(-4535 4310);
DISPLAY 0.638298 (-4535 4310);
PAINT ORANGE (-4535 4310);
WIRE 16 -1 (-3375 4450)(-4600 4450);
FORCEPROP 0 LAST $PHYS_NET_NAME CLK_50M_CKMNG_BMC_2
J 0
(-4460 4539);
PAINT MONO (-4460 4539);
DISPLAY INVISIBLE (-4460 4539);
FORCEPROP 0 LAST CDS_PHYS_NET_NAME CLK_50M_CKMNG_BMC_2
J 0
(-4460 4492);
PAINT MONO (-4460 4492);
DISPLAY INVISIBLE (-4460 4492);
FORCEPROP 2 LAST SIG_NAME CLK_50M_CKMNG_BMC_2
J 0
(-4535 4460);
DISPLAY 0.638298 (-4535 4460);
PAINT ORANGE (-4535 4460);
WIRE 16 -1 (-275 3200)(900 3200);
FORCEPROP 2 LAST SIG_NAME A_P3V_BAT_SCALED
J 0
(-135 3210);
DISPLAY 0.638298 (-135 3210);
PAINT ORANGE (-135 3210);
WIRE 16 -1 (-4600 3850)(-3375 3850);
FORCEPROP 2 LAST SIG_NAME RMII_BMC_OCP_CRSDV
J 0
(-4535 3860);
DISPLAY 0.638298 (-4535 3860);
PAINT ORANGE (-4535 3860);
WIRE 16 -1 (-4600 3900)(-3375 3900);
FORCEPROP 2 LAST SIG_NAME RMII_BMC_OCP_RXER
J 0
(-4535 3910);
DISPLAY 0.638298 (-4535 3910);
PAINT ORANGE (-4535 3910);
WIRE 16 -1 (-3375 2950)(-4050 2950);
FORCEPROP 2 LAST SIG_NAME FM_BOARD_SKU_ID4
J 0
(-3985 2960);
DISPLAY 0.638298 (-3985 2960);
PAINT ORANGE (-3985 2960);
WIRE 16 -1 (-3375 2750)(-4050 2750);
FORCEPROP 2 LAST SIG_NAME FM_BOARD_SKU_ID0
J 0
(-3985 2760);
DISPLAY 0.638298 (-3985 2760);
PAINT ORANGE (-3985 2760);
WIRE 16 -1 (-4050 2700)(-3375 2700);
FORCEPROP 2 LAST SIG_NAME FM_XRC_READY_N
J 0
(-3985 2710);
DISPLAY 0.638298 (-3985 2710);
PAINT ORANGE (-3985 2710);
WIRE 16 -1 (-4050 2650)(-3375 2650);
FORCEPROP 2 LAST SIG_NAME FM_XRC_PRESENT_N
J 0
(-3985 2660);
DISPLAY 0.638298 (-3985 2660);
PAINT ORANGE (-3985 2660);
WIRE 16 -1 (-4600 3750)(-3375 3750);
FORCEPROP 2 LAST SIG_NAME RMII_BMC_OCP_RXD0
J 0
(-4535 3760);
DISPLAY 0.638298 (-4535 3760);
PAINT ORANGE (-4535 3760);
WIRE 16 -1 (-4050 3100)(-3375 3100);
FORCEPROP 2 LAST SIG_NAME BMC_RSMRST_B_N
J 0
(-3985 3110);
DISPLAY 0.638298 (-3985 3110);
PAINT ORANGE (-3985 3110);
FORCEPROP 2 LASTPROP $XRERR UNIQUE?
J 0
(-4225 3110);
DISPLAY 0.638298 (-4225 3110);
PAINT MONO (-4225 3110);
DISPLAY INVISIBLE (-4225 3110);
WIRE 16 -1 (-4050 3000)(-3375 3000);
FORCEPROP 0 LAST CDS_PHYS_NET_NAME BMC_PREQ_N
J 0
(-3900 3039);
PAINT MONO (-3900 3039);
DISPLAY INVISIBLE (-3900 3039);
FORCEPROP 2 LAST SIG_NAME BMC_PREQ_N
J 0
(-3985 3010);
DISPLAY 0.638298 (-3985 3010);
PAINT ORANGE (-3985 3010);
WIRE 3 682 (-5150 3200)(-5200 3200);
WIRE 3 682 (-5100 3100)(-5150 3100);
WIRE 3 682 (-5200 3200)(-5200 3050);
WIRE 3 682 (-5200 3050)(-5150 3050);
WIRE 3 682 (-5150 3100)(-5150 3050);
WIRE 3 682 (-5150 3050)(-5150 2750);
WIRE 3 682 (-5150 2750)(-5100 2750);
WIRE 16 -1 (-4050 3050)(-3375 3050);
FORCEPROP 2 LAST SIG_NAME BMC_PWR_DEBUG_N
J 0
(-3985 3060);
DISPLAY 0.638298 (-3985 3060);
PAINT ORANGE (-3985 3060);
WIRE 16 -1 (-4650 3100)(-4250 3100);
FORCEPROP 2 LAST SIG_NAME RST_RSMRST_N
J 0
(-4585 3110);
DISPLAY 0.638298 (-4585 3110);
PAINT ORANGE (-4585 3110);
WIRE 16 -1 (-4600 3500)(-3375 3500);
FORCEPROP 2 LAST SIG_NAME FM_SLT_CFG0
J 0
(-4535 3510);
DISPLAY 0.638298 (-4535 3510);
PAINT ORANGE (-4535 3510);
WIRE 16 -1 (-4600 3450)(-3375 3450);
FORCEPROP 2 LAST SIG_NAME FM_SLT_CFG1
J 0
(-4535 3460);
DISPLAY 0.638298 (-4535 3460);
PAINT ORANGE (-4535 3460);
WIRE 16 -1 (-3375 2900)(-4050 2900);
FORCEPROP 2 LAST SIG_NAME FM_BOARD_SKU_ID3
J 0
(-3985 2910);
DISPLAY 0.638298 (-3985 2910);
PAINT ORANGE (-3985 2910);
WIRE 16 -1 (-3375 2850)(-4050 2850);
FORCEPROP 2 LAST SIG_NAME FM_BOARD_SKU_ID2
J 0
(-3985 2860);
DISPLAY 0.638298 (-3985 2860);
PAINT ORANGE (-3985 2860);
WIRE 16 -1 (-3375 2800)(-4050 2800);
FORCEPROP 2 LAST SIG_NAME FM_BOARD_SKU_ID1
J 0
(-3985 2810);
DISPLAY 0.638298 (-3985 2810);
PAINT ORANGE (-3985 2810);
WIRE 16 -1 (-4700 2600)(-4700 2050);
WIRE 16 -1 (-4800 2600)(-4700 2600);
WIRE 16 -1 (-4700 2600)(-3375 2600);
FORCEPROP 2 LAST SIG_NAME PUMP_TACH1
J 0
(-3985 2610);
DISPLAY 0.638298 (-3985 2610);
PAINT ORANGE (-3985 2610);
WIRE 16 -1 (-3500 2050)(-3500 2500);
WIRE 16 -1 (-3500 2500)(-3375 2500);
WIRE 16 -1 (-4800 2500)(-3500 2500);
FORCEPROP 2 LAST SIG_NAME FAN_TACH3
J 0
(-4485 2510);
DISPLAY 0.638298 (-4485 2510);
PAINT ORANGE (-4485 2510);
WIRE 16 -1 (-4800 2450)(-3800 2450);
FORCEPROP 2 LAST SIG_NAME FAN_TACH2
J 0
(-4485 2460);
DISPLAY 0.638298 (-4485 2460);
PAINT ORANGE (-4485 2460);
WIRE 16 -1 (-3800 2050)(-3800 2450);
WIRE 16 -1 (-3375 2450)(-3800 2450);
WIRE 16 -1 (-4800 2400)(-4100 2400);
FORCEPROP 2 LAST SIG_NAME FAN_TACH1
J 0
(-4485 2410);
DISPLAY 0.638298 (-4485 2410);
PAINT ORANGE (-4485 2410);
WIRE 16 -1 (-4100 2050)(-4100 2400);
WIRE 16 -1 (-3375 2400)(-4100 2400);
WIRE 16 -1 (-4750 1500)(-4750 1400);
WIRE 16 -1 (-4750 1500)(-4200 1500);
WIRE 16 -1 (-4750 2550)(-4750 1500);
WIRE 16 -1 (-4800 2550)(-4750 2550);
WIRE 16 -1 (-4750 2550)(-3375 2550);
FORCEPROP 2 LAST SIG_NAME PUMP_TACH0
J 0
(-4485 2560);
DISPLAY 0.638298 (-4485 2560);
PAINT ORANGE (-4485 2560);
WIRE 16 -1 (-4800 2350)(-4400 2350);
FORCEPROP 2 LAST SIG_NAME FAN_TACH0
J 0
(-4485 2360);
DISPLAY 0.638298 (-4485 2360);
PAINT ORANGE (-4485 2360);
WIRE 16 -1 (-4400 2050)(-4400 2350);
WIRE 16 -1 (-3375 2350)(-4400 2350);
WIRE 16 -1 (-275 3900)(1800 3900);
FORCEPROP 2 LAST SIG_NAME TP_RGMII1TXD3_GPIOT5
J 0
(-135 3910);
DISPLAY 0.638298 (-135 3910);
PAINT ORANGE (-135 3910);
WIRE 16 -1 (-275 3850)(1800 3850);
FORCEPROP 2 LAST SIG_NAME TP_RGMII1TXD2_GPIOT4
J 0
(-135 3860);
DISPLAY 0.638298 (-135 3860);
PAINT ORANGE (-135 3860);
WIRE 16 -1 (900 3800)(1800 3800);
FORCEPROP 2 LAST SIG_NAME RMII_BMC_OCP_TXD1
J 0
(1165 3810);
DISPLAY 0.638298 (1165 3810);
PAINT ORANGE (1165 3810);
WIRE 16 -1 (900 3750)(1800 3750);
FORCEPROP 2 LAST SIG_NAME RMII_BMC_OCP_TXD0
J 0
(1165 3760);
DISPLAY 0.638298 (1165 3760);
PAINT ORANGE (1165 3760);
WIRE 16 -1 (450 3650)(1800 3650);
WIRE 16 -1 (450 3800)(-275 3800);
FORCEPROP 2 LAST SIG_NAME RMII_BMC_OCP_TXD1_R
J 0
(-135 3810);
DISPLAY 0.638298 (-135 3810);
PAINT ORANGE (-135 3810);
WIRE 16 -1 (450 3650)(450 3800);
WIRE 16 -1 (700 3800)(450 3800);
WIRE 16 -1 (-275 3400)(1400 3400);
FORCEPROP 0 LAST SIG_NAME FM_GLOBAL_RST_WARN_N_R
J 0
(-125 3410);
DISPLAY 0.617021 (-125 3410);
PAINT ORANGE (-125 3410);
FORCEPROP 2 LASTPROP $XRERR UNIQUE?
J 0
(-365 3410);
DISPLAY 0.638298 (-365 3410);
PAINT MONO (-365 3410);
DISPLAY INVISIBLE (-365 3410);
WIRE 3 273 (1350 3500)(1350 2850);
WIRE 3 273 (1650 3500)(1350 3500);
WIRE 3 273 (1350 2850)(1650 2850);
WIRE 3 273 (1650 2850)(1650 3500);
WIRE 16 -1 (2250 3400)(1600 3400);
FORCEPROP 0 LAST SIG_NAME FM_GLOBAL_RST_WARN_N
J 0
(1700 3410);
DISPLAY 0.617021 (1700 3410);
PAINT ORANGE (1700 3410);
WIRE 16 -1 (2250 4150)(1100 4150);
FORCEPROP 2 LAST SIG_NAME RMII_BMC_PCH_SPRNGVLLE_TXD0
J 0
(1365 4160);
DISPLAY 0.638298 (1365 4160);
PAINT ORANGE (1365 4160);
DOT 1 (-4750 2550);
DOT 1 (-4400 2350);
DOT 1 (-3500 2500);
DOT 1 (-3800 2450);
DOT 1 (-4100 2400);
DOT 1 (-5150 3050);
DOT 1 (-2850 2550);
DOT 1 (-3600 4150);
DOT 1 (700 4200);
DOT 1 (650 4150);
DOT 1 (450 3800);
DOT 1 (-150 2500);
DOT 1 (-3900 4200);
DOT 1 (-3900 5150);
DOT 1 (500 3750);
DOT 1 (-150 3350);
DOT 1 (1450 2300);
DOT 1 (1450 1950);
DOT 1 (-150 3300);
DOT 1 (-4750 1500);
DOT 1 (-4700 2600);
FORCENOTE
TP FAB1 ADD POTENTIAL DEBUG USE  0128
(1325 3525) 0;
DISPLAY LEFT (1325 3525);
DISPLAY 1.021277 (1325 3525);
PAINT RED (1325 3525);
FORCENOTE
TP FAB3 RECONNECT 0920
(-5125 3200) 0;
DISPLAY LEFT (-5125 3200);
DISPLAY 0.638298 (-5125 3200);
PAINT RED (-5125 3200);
FORCENOTE
TP FAB3 RECONNECT 0922
(-5125 3150) 0;
DISPLAY LEFT (-5125 3150);
DISPLAY 0.638298 (-5125 3150);
PAINT RED (-5125 3150);
FORCENOTE
TP FAB3 RECONNECTION 0831
(-2750 2550) 0;
DISPLAY LEFT (-2750 2550);
DISPLAY 0.638298 (-2750 2550);
PAINT RED (-2750 2550);
FORCENOTE
TP FAB1 POP CAP 0331
(1400 1750) 0;
DISPLAY LEFT (1400 1750);
DISPLAY 1.021277 (1400 1750);
PAINT RED (1400 1750);
FORCENOTE
TP FAB1 RENAME RGMII2TX2, TX3 0227
(350 4325) 0;
DISPLAY LEFT (350 4325);
DISPLAY 1.021277 (350 4325);
PAINT RED (350 4325);
FORCENOTE
TP FAB1 NOPOP RES 0227
(1700 5150) 0;
DISPLAY LEFT (1700 5150);
DISPLAY 1.021277 (1700 5150);
PAINT RED (1700 5150);
FORCENOTE
ROOM=SM_CONTROLLER
(-5083 798) 0;
DISPLAY LEFT (-5083 798);
DISPLAY 0.617021 (-5083 798);
PAINT PURPLE (-5083 798);
FORCENOTE
TP FAB3 ADD RES 0819
(-4800 1000) 0;
DISPLAY LEFT (-4800 1000);
DISPLAY 0.638298 (-4800 1000);
PAINT RED (-4800 1000);
FORCENOTE
TP FAB3 ADD RES 0831
(-4800 900) 0;
DISPLAY LEFT (-4800 900);
DISPLAY 0.638298 (-4800 900);
PAINT RED (-4800 900);
FORCENOTE
TP FAB3 DEL RES 0823
(-4800 950) 0;
DISPLAY LEFT (-4800 950);
DISPLAY 0.638298 (-4800 950);
PAINT RED (-4800 950);
FORCENOTE
TP FAB1 DEL RES 0301
(1700 5075) 0;
DISPLAY LEFT (1700 5075);
DISPLAY 1.021277 (1700 5075);
PAINT RED (1700 5075);
FORCENOTE
TP FAB1 NC 0314
(-3550 4525) 0;
DISPLAY LEFT (-3550 4525);
DISPLAY 1.021277 (-3550 4525);
PAINT RED (-3550 4525);
FORCENOTE
TP FAB1 ADD RES 0121
(-4425 1675) 0;
DISPLAY LEFT (-4425 1675);
DISPLAY 1.021277 (-4425 1675);
PAINT RED (-4425 1675);
QUIT
